FILE_TYPE = MACRO_DRAWING;
SET COLOR_WIRE YELLOW;
SET COLOR_PROP ORANGE;
SET COLOR_DOT WHITE;
SET COLOR_ARC YELLOW;
SET COLOR_BODY GREEN;
SET COLOR_NOTE PURPLE;
SET PROP_DISPLAY VALUE;
SET PAGE_NUMBER P46;
SET PATH_NUMBER P147;
FORCEADD OFFPAGE..2
(-5425 -5600);
FORCEPROP 2 LAST $XR1 34 
J 0
(-5146 -5600);
DISPLAY 0.638298 (-5146 -5600);
PAINT MONO (-5146 -5600);
FORCEPROP 2 LAST $XR0 15 
J 0
(-5236 -5600);
DISPLAY 0.638298 (-5236 -5600);
PAINT MONO (-5236 -5600);
FORCEPROP 2 LAST CDS_LIB standard
J 0
(-5425 -5600);
DISPLAY INVISIBLE (-5425 -5600);
FORCEPROP 1 LAST OFFPAGE TRUE
J 0
(-5100 -5725);
DISPLAY 0.872340 (-5100 -5725);
PAINT GREEN (-5100 -5725);
DISPLAY INVISIBLE (-5100 -5725);
FORCEPROP 1 LAST COMMENT_BODY TRUE
J 0
(-5470 -5695);
DISPLAY 0.872340 (-5470 -5695);
PAINT PEACH (-5470 -5695);
DISPLAY INVISIBLE (-5470 -5695);
FORCEPROP 2 LAST PATH I100
J 0
(-5225 -5550);
DISPLAY 1.021277 (-5225 -5550);
DISPLAY INVISIBLE (-5225 -5550);
FORCEADD Q_CAP..1
(-6875 -4425);
FORCEPROP 1 LAST TOLERANCE 10%
J 0
(-6825 -4475);
DISPLAY 0.510638 (-6825 -4475);
PAINT SKYBLUE (-6825 -4475);
FORCEPROP 1 LAST MATERIAL X7R
J 0
(-6825 -4525);
DISPLAY 0.510638 (-6825 -4525);
PAINT SKYBLUE (-6825 -4525);
FORCEPROP 1 LAST VOLTAGE 25V
J 0
(-6825 -4425);
DISPLAY 0.510638 (-6825 -4425);
PAINT SKYBLUE (-6825 -4425);
FORCEPROP 1 LAST VALUE 0.1UF
J 0
(-6825 -4375);
DISPLAY 0.510638 (-6825 -4375);
PAINT SKYBLUE (-6825 -4375);
FORCEPROP 1 LAST PART_NUMBER CH4104K1B00
J 0
(-6825 -4575);
DISPLAY 0.510638 (-6825 -4575);
PAINT WHITE (-6825 -4575);
FORCEPROP 1 LAST PACK_TYPE 0402
J 0
(-6825 -4625);
DISPLAY 0.510638 (-6825 -4625);
PAINT SKYBLUE (-6825 -4625);
FORCEPROP 1 LAST PATH I102
J 0
(-6825 -4275);
DISPLAY 0.978723 (-6825 -4275);
PAINT WHITE (-6825 -4275);
DISPLAY INVISIBLE (-6825 -4275);
FORCEPROP 2 LAST CDS_LIB pure_quanta
J 0
(-6875 -4425);
DISPLAY INVISIBLE (-6875 -4425);
FORCEPROP 1 LAST LOCATION C144
J 0
(-6825 -4325);
DISPLAY 0.702128 (-6825 -4325);
PAINT YELLOW (-6825 -4325);
FORCEPROP 0 LAST $SEC 1
J 0
(-6825 -4275);
DISPLAY 0.680851 (-6825 -4275);
PAINT MONO (-6825 -4275);
DISPLAY INVISIBLE (-6825 -4275);
FORCEPROP 0 LAST CDS_SEC 1
J 0
(-6825 -4275);
DISPLAY 1.021277 (-6825 -4275);
DISPLAY INVISIBLE (-6825 -4275);
FORCEPROP 1 LASTPIN (-6875 -4325) $PN 1
J 0
(-6865 -4345);
DISPLAY 0.808511 (-6865 -4345);
PAINT WHITE (-6865 -4345);
DISPLAY INVISIBLE (-6865 -4345);
FORCEPROP 1 LASTPIN (-6875 -4525) $PN 2
J 0
(-6865 -4545);
DISPLAY 0.808511 (-6865 -4545);
PAINT WHITE (-6865 -4545);
DISPLAY INVISIBLE (-6865 -4545);
FORCEADD Q_RES..2
R 2
(-6300 -5325);
FORCEPROP 1 LAST VALUE 10K
J 2
(-6345 -5250);
DISPLAY 0.510638 (-6345 -5250);
PAINT SKYBLUE (-6345 -5250);
FORCEPROP 1 LAST TOLERANCE 1%
J 2
(-6345 -5300);
DISPLAY 0.510638 (-6345 -5300);
PAINT SKYBLUE (-6345 -5300);
FORCEPROP 1 LAST PACK_TYPE 0402LF
J 2
(-6340 -5500);
DISPLAY 0.510638 (-6340 -5500);
PAINT SKYBLUE (-6340 -5500);
FORCEPROP 1 LAST PART_NUMBER CS31002FB08
J 2
(-6340 -5450);
DISPLAY 0.510638 (-6340 -5450);
PAINT WHITE (-6340 -5450);
FORCEPROP 1 LAST MATERIAL CHIP
J 2
(-6340 -5400);
DISPLAY 0.510638 (-6340 -5400);
PAINT SKYBLUE (-6340 -5400);
FORCEPROP 1 LAST WATTAGE 1/16W
J 2
(-6340 -5350);
DISPLAY 0.510638 (-6340 -5350);
PAINT SKYBLUE (-6340 -5350);
FORCEPROP 1 LAST PATH I104
J 2
(-6350 -5150);
DISPLAY 0.978723 (-6350 -5150);
PAINT WHITE (-6350 -5150);
DISPLAY INVISIBLE (-6350 -5150);
FORCEPROP 2 LAST CDS_LIB pure_quanta
J 2
(-6300 -5325);
DISPLAY INVISIBLE (-6300 -5325);
FORCEPROP 1 LAST LOCATION R50
J 2
(-6345 -5200);
DISPLAY 0.702128 (-6345 -5200);
PAINT YELLOW (-6345 -5200);
FORCEPROP 0 LAST $SEC 1
J 2
(-6350 -5150);
DISPLAY 0.680851 (-6350 -5150);
PAINT MONO (-6350 -5150);
DISPLAY INVISIBLE (-6350 -5150);
FORCEPROP 0 LAST CDS_SEC 1
J 2
(-6350 -5150);
DISPLAY 1.021277 (-6350 -5150);
DISPLAY INVISIBLE (-6350 -5150);
FORCEPROP 1 LASTPIN (-6300 -5225) $PN 1
J 2
(-6305 -5263);
DISPLAY 0.808511 (-6305 -5263);
PAINT WHITE (-6305 -5263);
DISPLAY INVISIBLE (-6305 -5263);
FORCEPROP 1 LASTPIN (-6300 -5425) $PN 2
J 2
(-6305 -5415);
DISPLAY 0.808511 (-6305 -5415);
PAINT WHITE (-6305 -5415);
DISPLAY INVISIBLE (-6305 -5415);
FORCEADD Q_RES..1
R 2
(-6600 -5650);
FORCEPROP 1 LAST MATERIAL CHIP
J 2
(-6325 -5650);
DISPLAY 0.510638 (-6325 -5650);
PAINT SKYBLUE (-6325 -5650);
FORCEPROP 1 LAST VALUE 0
J 0
(-6500 -5650);
DISPLAY 0.510638 (-6500 -5650);
PAINT SKYBLUE (-6500 -5650);
FORCEPROP 1 LAST PART_NUMBER CS00002JB13
J 2
(-6350 -5625);
DISPLAY 0.510638 (-6350 -5625);
PAINT WHITE (-6350 -5625);
DISPLAY INVISIBLE (-6350 -5625);
FORCEPROP 1 LAST PACK_TYPE 0402LF
J 2
(-6000 -5675);
DISPLAY 0.510638 (-6000 -5675);
PAINT SKYBLUE (-6000 -5675);
DISPLAY INVISIBLE (-6000 -5675);
FORCEPROP 1 LAST WATTAGE 1/16W
J 0
(-6300 -5675);
DISPLAY 0.510638 (-6300 -5675);
PAINT SKYBLUE (-6300 -5675);
DISPLAY INVISIBLE (-6300 -5675);
FORCEPROP 1 LAST PATH I105
J 2
(-6550 -5500);
DISPLAY 0.978723 (-6550 -5500);
PAINT WHITE (-6550 -5500);
DISPLAY INVISIBLE (-6550 -5500);
FORCEPROP 1 LAST TOLERANCE 5%
J 2
(-6450 -5675);
DISPLAY 0.510638 (-6450 -5675);
PAINT SKYBLUE (-6450 -5675);
DISPLAY INVISIBLE (-6450 -5675);
FORCEPROP 2 LAST SEC_TYPE 0402LF
J 0
(-6550 -5450);
DISPLAY 1.021277 (-6550 -5450);
DISPLAY INVISIBLE (-6550 -5450);
FORCEPROP 2 LAST CDS_LIB pure_quanta
J 0
(-6600 -5650);
DISPLAY INVISIBLE (-6600 -5650);
FORCEPROP 1 LAST LOCATION R113
J 2
(-6700 -5650);
DISPLAY 0.702128 (-6700 -5650);
PAINT YELLOW (-6700 -5650);
FORCEPROP 1 LASTPIN (-6500 -5650) $PN 1
J 2
(-6512 -5638);
DISPLAY 0.808511 (-6512 -5638);
PAINT WHITE (-6512 -5638);
FORCEPROP 1 LASTPIN (-6700 -5650) $PN 2
J 2
(-6662 -5638);
DISPLAY 0.808511 (-6662 -5638);
PAINT WHITE (-6662 -5638);
FORCEPROP 0 LAST SEC 1
J 0
(-6700 -5600);
DISPLAY 0.680851 (-6700 -5600);
PAINT MONO (-6700 -5600);
DISPLAY INVISIBLE (-6700 -5600);
FORCEADD Q_RES..1
R 6
(-6600 -5700);
FORCEPROP 1 LAST VALUE 33.2
J 2
(-6450 -5700);
DISPLAY 0.510638 (-6450 -5700);
PAINT SKYBLUE (-6450 -5700);
FORCEPROP 1 LAST MATERIAL CHIP
J 0
(-6425 -5700);
DISPLAY 0.510638 (-6425 -5700);
PAINT SKYBLUE (-6425 -5700);
FORCEPROP 1 LAST TOLERANCE 1%
J 0
(-6150 -5800);
DISPLAY 0.510638 (-6150 -5800);
PAINT SKYBLUE (-6150 -5800);
FORCEPROP 1 LAST PART_NUMBER CS03322FB03
J 0
(-6750 -5800);
DISPLAY 0.510638 (-6750 -5800);
PAINT WHITE (-6750 -5800);
FORCEPROP 1 LAST WATTAGE 1/16W
J 2
(-6175 -5800);
DISPLAY 0.510638 (-6175 -5800);
PAINT SKYBLUE (-6175 -5800);
FORCEPROP 1 LAST PACK_TYPE 0402LF
J 0
(-6475 -5800);
DISPLAY 0.510638 (-6475 -5800);
PAINT SKYBLUE (-6475 -5800);
FORCEPROP 2 LAST CDS_LIB pure_quanta
J 0
(-6600 -5747);
DISPLAY INVISIBLE (-6600 -5747);
FORCEPROP 1 LAST PATH I106
J 0
(-6650 -5850);
DISPLAY 0.978723 (-6650 -5850);
PAINT WHITE (-6650 -5850);
DISPLAY INVISIBLE (-6650 -5850);
FORCEPROP 1 LAST LOCATION R47
J 0
(-6775 -5700);
DISPLAY 0.702128 (-6775 -5700);
PAINT YELLOW (-6775 -5700);
FORCEPROP 1 LASTPIN (-6700 -5700) $PN 1
J 0
(-6688 -5750);
DISPLAY 0.808511 (-6688 -5750);
PAINT WHITE (-6688 -5750);
FORCEPROP 1 LASTPIN (-6500 -5700) $PN 2
J 0
(-6538 -5750);
DISPLAY 0.808511 (-6538 -5750);
PAINT WHITE (-6538 -5750);
FORCEPROP 0 LAST $SEC 1
J 0
(-6850 -5882);
DISPLAY 0.680851 (-6850 -5882);
PAINT MONO (-6850 -5882);
DISPLAY INVISIBLE (-6850 -5882);
FORCEPROP 0 LAST CDS_SEC 1
J 0
(-6850 -5898);
DISPLAY 1.021277 (-6850 -5898);
DISPLAY INVISIBLE (-6850 -5898);
FORCEADD UNIVERSAL_POWER..1
(-7250 -4125);
FORCEPROP 3 LASTPIN (-7250 -4175) SIG_NAME P3V3_AUX\g
J 0
(-7240 -4165);
DISPLAY 0.659574 (-7240 -4165);
PAINT MONO (-7240 -4165);
DISPLAY INVISIBLE (-7240 -4165);
FORCEPROP 1 LAST HDL_POWER P3V3_AUX
J 1
(-7250 -4075);
DISPLAY 0.702128 (-7250 -4075);
PAINT PEACH (-7250 -4075);
FORCEPROP 1 LAST PATH I107
J 0
(-7200 -4100);
DISPLAY 0.872340 (-7200 -4100);
PAINT AQUA (-7200 -4100);
DISPLAY INVISIBLE (-7200 -4100);
FORCEPROP 2 LAST CDS_LIB logical_power
J 0
(-7250 -4125);
DISPLAY INVISIBLE (-7250 -4125);
FORCEADD Q_CAP..1
(-7250 -4425);
FORCEPROP 1 LAST PACK_TYPE C0402
J 0
(-7200 -4625);
DISPLAY 0.510638 (-7200 -4625);
PAINT SKYBLUE (-7200 -4625);
FORCEPROP 1 LAST VALUE 10UF
J 0
(-7200 -4375);
DISPLAY 0.510638 (-7200 -4375);
PAINT SKYBLUE (-7200 -4375);
FORCEPROP 1 LAST TOLERANCE 20%
J 0
(-7200 -4475);
DISPLAY 0.510638 (-7200 -4475);
PAINT SKYBLUE (-7200 -4475);
FORCEPROP 1 LAST MATERIAL X6S
J 0
(-7200 -4525);
DISPLAY 0.510638 (-7200 -4525);
PAINT SKYBLUE (-7200 -4525);
FORCEPROP 1 LAST PART_NUMBER CH6101MEB01
J 0
(-7200 -4575);
DISPLAY 0.510638 (-7200 -4575);
PAINT WHITE (-7200 -4575);
FORCEPROP 1 LAST VOLTAGE 6.3V
J 0
(-7200 -4425);
DISPLAY 0.510638 (-7200 -4425);
PAINT SKYBLUE (-7200 -4425);
FORCEPROP 1 LAST PATH I108
J 0
(-7200 -4275);
DISPLAY 0.978723 (-7200 -4275);
PAINT WHITE (-7200 -4275);
DISPLAY INVISIBLE (-7200 -4275);
FORCEPROP 2 LAST CDS_LIB pure_quanta
J 0
(-7250 -4425);
DISPLAY INVISIBLE (-7250 -4425);
FORCEPROP 1 LAST LOCATION C143
J 0
(-7200 -4325);
DISPLAY 0.702128 (-7200 -4325);
PAINT YELLOW (-7200 -4325);
FORCEPROP 0 LAST $SEC 1
J 0
(-7200 -4275);
DISPLAY 0.680851 (-7200 -4275);
PAINT MONO (-7200 -4275);
DISPLAY INVISIBLE (-7200 -4275);
FORCEPROP 0 LAST CDS_SEC 1
J 0
(-7200 -4275);
DISPLAY 1.021277 (-7200 -4275);
DISPLAY INVISIBLE (-7200 -4275);
FORCEPROP 1 LASTPIN (-7250 -4325) $PN 1
J 0
(-7240 -4345);
DISPLAY 0.808511 (-7240 -4345);
PAINT WHITE (-7240 -4345);
DISPLAY INVISIBLE (-7240 -4345);
FORCEPROP 1 LASTPIN (-7250 -4525) $PN 2
J 0
(-7240 -4545);
DISPLAY 0.808511 (-7240 -4545);
PAINT WHITE (-7240 -4545);
DISPLAY INVISIBLE (-7240 -4545);
FORCEADD UNIVERSAL_GND..1
(-7250 -4875);
FORCEPROP 3 LASTPIN (-7250 -4825) SIG_NAME GND\g
J 0
(-7240 -4815);
DISPLAY 0.659574 (-7240 -4815);
PAINT MONO (-7240 -4815);
DISPLAY INVISIBLE (-7240 -4815);
FORCEPROP 1 LAST PATH I109
J 0
(-7175 -4875);
DISPLAY 0.872340 (-7175 -4875);
PAINT AQUA (-7175 -4875);
DISPLAY INVISIBLE (-7175 -4875);
FORCEPROP 1 LAST HDL_POWER GND
J 1
(-7225 -4950);
DISPLAY 0.702128 (-7225 -4950);
PAINT GREEN (-7225 -4950);
DISPLAY INVISIBLE (-7225 -4950);
FORCEPROP 2 LAST CDS_LIB logical_power
J 0
(-7250 -4875);
DISPLAY INVISIBLE (-7250 -4875);
FORCEADD UNIVERSAL_GND..1
(-7525 -6100);
FORCEPROP 3 LASTPIN (-7525 -6050) SIG_NAME GND\g
J 0
(-7515 -6040);
DISPLAY 0.659574 (-7515 -6040);
PAINT MONO (-7515 -6040);
DISPLAY INVISIBLE (-7515 -6040);
FORCEPROP 1 LAST PATH I112
J 0
(-7450 -6100);
DISPLAY 0.872340 (-7450 -6100);
PAINT AQUA (-7450 -6100);
DISPLAY INVISIBLE (-7450 -6100);
FORCEPROP 1 LAST HDL_POWER GND
J 1
(-7500 -6175);
DISPLAY 0.702128 (-7500 -6175);
PAINT GREEN (-7500 -6175);
DISPLAY INVISIBLE (-7500 -6175);
FORCEPROP 2 LAST CDS_LIB logical_power
J 0
(-7525 -6100);
DISPLAY INVISIBLE (-7525 -6100);
FORCEADD SCONN11_9192031111LF..1
(-7950 -5725);
FORCEPROP 1 LAST MATERIAL IO
J 0
(-8094 -5418);
DISPLAY 0.510638 (-8094 -5418);
PAINT SKYBLUE (-8094 -5418);
FORCEPROP 1 LAST PART_NUMBER DFHS11FS009
J 0
(-8094 -5291);
DISPLAY 0.510638 (-8094 -5291);
PAINT WHITE (-8094 -5291);
FORCEPROP 2 LAST PART_TYPE SMLF
J 0
(-8075 -5050);
DISPLAY 0.510638 (-8075 -5050);
PAINT SKYBLUE (-8075 -5050);
FORCEPROP 2 LAST VALUE SCONN11_91920-31111LF
J 0
(-8075 -5100);
DISPLAY 0.510638 (-8075 -5100);
PAINT SKYBLUE (-8075 -5100);
FORCEPROP 1 LAST PATH I113
J 0
(-7950 -5725);
DISPLAY 0.723404 (-7950 -5725);
PAINT GREEN (-7950 -5725);
DISPLAY INVISIBLE (-7950 -5725);
FORCEPROP 1 LAST CDS_LMAN_SYM_OUTLINE -150,275,150,-275
J 0
(-7950 -5725);
DISPLAY 0.468085 (-7950 -5725);
PAINT GREEN (-7950 -5725);
DISPLAY INVISIBLE (-7950 -5725);
FORCEPROP 1 LAST NEEDS_NO_SIZE TRUE
J 0
(-7950 -5725);
DISPLAY 0.723404 (-7950 -5725);
PAINT GREEN (-7950 -5725);
DISPLAY INVISIBLE (-7950 -5725);
FORCEPROP 2 LAST CDS_LIB pure_quanta
J 0
(-7950 -5725);
DISPLAY INVISIBLE (-7950 -5725);
FORCEPROP 1 LAST LOCATION J10
J 0
(-8094 -5144);
DISPLAY 0.702128 (-8094 -5144);
PAINT YELLOW (-8094 -5144);
FORCEPROP 0 LASTPIN (-8250 -5550) $PN 1
J 2
(-8260 -5540);
DISPLAY 0.680851 (-8260 -5540);
PAINT MONO (-8260 -5540);
FORCEPROP 0 LASTPIN (-8250 -5600) $PN 2
J 2
(-8260 -5590);
DISPLAY 0.680851 (-8260 -5590);
PAINT MONO (-8260 -5590);
FORCEPROP 0 LASTPIN (-8250 -5650) $PN 3
J 2
(-8260 -5640);
DISPLAY 0.680851 (-8260 -5640);
PAINT MONO (-8260 -5640);
FORCEPROP 0 LASTPIN (-8250 -5700) $PN 4
J 2
(-8260 -5690);
DISPLAY 0.680851 (-8260 -5690);
PAINT MONO (-8260 -5690);
FORCEPROP 0 LASTPIN (-8250 -5750) $PN 5
J 2
(-8260 -5740);
DISPLAY 0.680851 (-8260 -5740);
PAINT MONO (-8260 -5740);
FORCEPROP 0 LASTPIN (-8250 -5800) $PN 6
J 2
(-8260 -5790);
DISPLAY 0.680851 (-8260 -5790);
PAINT MONO (-8260 -5790);
FORCEPROP 0 LASTPIN (-7650 -5550) $PN 7
J 0
(-7640 -5540);
DISPLAY 0.680851 (-7640 -5540);
PAINT MONO (-7640 -5540);
FORCEPROP 0 LASTPIN (-7650 -5600) $PN 8
J 0
(-7640 -5590);
DISPLAY 0.680851 (-7640 -5590);
PAINT MONO (-7640 -5590);
FORCEPROP 0 LASTPIN (-7650 -5650) $PN 9
J 0
(-7640 -5640);
DISPLAY 0.680851 (-7640 -5640);
PAINT MONO (-7640 -5640);
FORCEPROP 0 LASTPIN (-7650 -5700) $PN 10
J 0
(-7640 -5690);
DISPLAY 0.680851 (-7640 -5690);
PAINT MONO (-7640 -5690);
FORCEPROP 0 LASTPIN (-7650 -5750) $PN 11
J 0
(-7640 -5740);
DISPLAY 0.680851 (-7640 -5740);
PAINT MONO (-7640 -5740);
FORCEPROP 0 LASTPIN (-7650 -5850) $PN G1
J 0
(-7640 -5840);
DISPLAY 0.680851 (-7640 -5840);
PAINT MONO (-7640 -5840);
FORCEPROP 0 LASTPIN (-7650 -5900) $PN G2
J 0
(-7640 -5890);
DISPLAY 0.680851 (-7640 -5890);
PAINT MONO (-7640 -5890);
FORCEPROP 0 LAST $SEC 1
J 0
(-8075 -5025);
DISPLAY 0.680851 (-8075 -5025);
PAINT MONO (-8075 -5025);
DISPLAY INVISIBLE (-8075 -5025);
FORCEPROP 0 LAST CDS_SEC 1
J 0
(-8075 -5025);
DISPLAY 1.021277 (-8075 -5025);
DISPLAY INVISIBLE (-8075 -5025);
FORCEADD Q_RES..1
R 2
(-9900 -5550);
FORCEPROP 1 LAST PACK_TYPE 0402LF
J 2
(-9300 -5575);
DISPLAY 0.510638 (-9300 -5575);
PAINT SKYBLUE (-9300 -5575);
FORCEPROP 1 LAST MATERIAL CHIP
J 2
(-9625 -5575);
DISPLAY 0.510638 (-9625 -5575);
PAINT SKYBLUE (-9625 -5575);
FORCEPROP 1 LAST WATTAGE 1/16W
J 0
(-9600 -5575);
DISPLAY 0.510638 (-9600 -5575);
PAINT SKYBLUE (-9600 -5575);
FORCEPROP 1 LAST VALUE 0
J 0
(-9850 -5575);
DISPLAY 0.510638 (-9850 -5575);
PAINT SKYBLUE (-9850 -5575);
FORCEPROP 1 LAST TOLERANCE 5%
J 2
(-9750 -5575);
DISPLAY 0.510638 (-9750 -5575);
PAINT SKYBLUE (-9750 -5575);
FORCEPROP 1 LAST PART_NUMBER CS00002JB13
J 2
(-9650 -5525);
DISPLAY 0.510638 (-9650 -5525);
PAINT WHITE (-9650 -5525);
DISPLAY INVISIBLE (-9650 -5525);
FORCEPROP 1 LAST PATH I114
J 2
(-9850 -5400);
DISPLAY 0.978723 (-9850 -5400);
PAINT WHITE (-9850 -5400);
DISPLAY INVISIBLE (-9850 -5400);
FORCEPROP 2 LAST CDS_LIB pure_quanta
J 0
(-9900 -5550);
DISPLAY INVISIBLE (-9900 -5550);
FORCEPROP 1 LAST LOCATION R109
J 2
(-9950 -5550);
DISPLAY 0.702128 (-9950 -5550);
PAINT YELLOW (-9950 -5550);
FORCEPROP 0 LAST $SEC 1
J 0
(-9950 -5500);
DISPLAY 0.680851 (-9950 -5500);
PAINT MONO (-9950 -5500);
DISPLAY INVISIBLE (-9950 -5500);
FORCEPROP 0 LAST CDS_SEC 1
J 0
(-9950 -5500);
DISPLAY 1.021277 (-9950 -5500);
DISPLAY INVISIBLE (-9950 -5500);
FORCEPROP 1 LASTPIN (-9800 -5550) $PN 1
J 2
(-9812 -5538);
DISPLAY 0.808511 (-9812 -5538);
PAINT WHITE (-9812 -5538);
DISPLAY INVISIBLE (-9812 -5538);
FORCEPROP 1 LASTPIN (-10000 -5550) $PN 2
J 2
(-9962 -5538);
DISPLAY 0.808511 (-9962 -5538);
PAINT WHITE (-9962 -5538);
DISPLAY INVISIBLE (-9962 -5538);
FORCEADD Q_RES..1
R 2
(-9900 -5650);
FORCEPROP 1 LAST PACK_TYPE 0402LF
J 2
(-9300 -5675);
DISPLAY 0.510638 (-9300 -5675);
PAINT SKYBLUE (-9300 -5675);
FORCEPROP 1 LAST MATERIAL CHIP
J 2
(-9625 -5675);
DISPLAY 0.510638 (-9625 -5675);
PAINT SKYBLUE (-9625 -5675);
FORCEPROP 1 LAST WATTAGE 1/16W
J 0
(-9600 -5675);
DISPLAY 0.510638 (-9600 -5675);
PAINT SKYBLUE (-9600 -5675);
FORCEPROP 1 LAST VALUE 0
J 0
(-9850 -5675);
DISPLAY 0.510638 (-9850 -5675);
PAINT SKYBLUE (-9850 -5675);
FORCEPROP 1 LAST TOLERANCE 5%
J 2
(-9750 -5675);
DISPLAY 0.510638 (-9750 -5675);
PAINT SKYBLUE (-9750 -5675);
FORCEPROP 1 LAST PART_NUMBER CS00002JB13
J 2
(-9650 -5625);
DISPLAY 0.510638 (-9650 -5625);
PAINT WHITE (-9650 -5625);
DISPLAY INVISIBLE (-9650 -5625);
FORCEPROP 1 LAST PATH I115
J 2
(-9850 -5500);
DISPLAY 0.978723 (-9850 -5500);
PAINT WHITE (-9850 -5500);
DISPLAY INVISIBLE (-9850 -5500);
FORCEPROP 2 LAST CDS_LIB pure_quanta
J 0
(-9900 -5650);
DISPLAY INVISIBLE (-9900 -5650);
FORCEPROP 1 LAST LOCATION R97
J 2
(-9950 -5650);
DISPLAY 0.702128 (-9950 -5650);
PAINT YELLOW (-9950 -5650);
FORCEPROP 0 LAST $SEC 1
J 0
(-9950 -5600);
DISPLAY 0.680851 (-9950 -5600);
PAINT MONO (-9950 -5600);
DISPLAY INVISIBLE (-9950 -5600);
FORCEPROP 0 LAST CDS_SEC 1
J 0
(-9950 -5600);
DISPLAY 1.021277 (-9950 -5600);
DISPLAY INVISIBLE (-9950 -5600);
FORCEPROP 1 LASTPIN (-9800 -5650) $PN 1
J 2
(-9812 -5638);
DISPLAY 0.808511 (-9812 -5638);
PAINT WHITE (-9812 -5638);
DISPLAY INVISIBLE (-9812 -5638);
FORCEPROP 1 LASTPIN (-10000 -5650) $PN 2
J 2
(-9962 -5638);
DISPLAY 0.808511 (-9962 -5638);
PAINT WHITE (-9962 -5638);
DISPLAY INVISIBLE (-9962 -5638);
FORCEADD Q_RES..1
R 2
(-9900 -5600);
FORCEPROP 1 LAST WATTAGE 1/16W
J 0
(-9600 -5625);
DISPLAY 0.510638 (-9600 -5625);
PAINT SKYBLUE (-9600 -5625);
FORCEPROP 1 LAST PACK_TYPE 0402LF
J 2
(-9300 -5625);
DISPLAY 0.510638 (-9300 -5625);
PAINT SKYBLUE (-9300 -5625);
FORCEPROP 1 LAST MATERIAL CHIP
J 2
(-9625 -5625);
DISPLAY 0.510638 (-9625 -5625);
PAINT SKYBLUE (-9625 -5625);
FORCEPROP 1 LAST VALUE 0
J 0
(-9850 -5625);
DISPLAY 0.510638 (-9850 -5625);
PAINT SKYBLUE (-9850 -5625);
FORCEPROP 1 LAST TOLERANCE 5%
J 2
(-9750 -5625);
DISPLAY 0.510638 (-9750 -5625);
PAINT SKYBLUE (-9750 -5625);
FORCEPROP 1 LAST PART_NUMBER CS00002JB13
J 2
(-9650 -5575);
DISPLAY 0.510638 (-9650 -5575);
PAINT WHITE (-9650 -5575);
DISPLAY INVISIBLE (-9650 -5575);
FORCEPROP 1 LAST PATH I116
J 2
(-9850 -5450);
DISPLAY 0.978723 (-9850 -5450);
PAINT WHITE (-9850 -5450);
DISPLAY INVISIBLE (-9850 -5450);
FORCEPROP 2 LAST CDS_LIB pure_quanta
J 0
(-9900 -5600);
DISPLAY INVISIBLE (-9900 -5600);
FORCEPROP 1 LAST LOCATION R110
J 2
(-9950 -5600);
DISPLAY 0.702128 (-9950 -5600);
PAINT YELLOW (-9950 -5600);
FORCEPROP 0 LAST $SEC 1
J 0
(-9950 -5550);
DISPLAY 0.680851 (-9950 -5550);
PAINT MONO (-9950 -5550);
DISPLAY INVISIBLE (-9950 -5550);
FORCEPROP 0 LAST CDS_SEC 1
J 0
(-9950 -5550);
DISPLAY 1.021277 (-9950 -5550);
DISPLAY INVISIBLE (-9950 -5550);
FORCEPROP 1 LASTPIN (-9800 -5600) $PN 1
J 2
(-9812 -5588);
DISPLAY 0.808511 (-9812 -5588);
PAINT WHITE (-9812 -5588);
DISPLAY INVISIBLE (-9812 -5588);
FORCEPROP 1 LASTPIN (-10000 -5600) $PN 2
J 2
(-9962 -5588);
DISPLAY 0.808511 (-9962 -5588);
PAINT WHITE (-9962 -5588);
DISPLAY INVISIBLE (-9962 -5588);
FORCEADD Q_RES..1
(-9900 -5800);
FORCEPROP 1 LAST VALUE 33.2
J 2
(-9525 -5825);
DISPLAY 0.510638 (-9525 -5825);
PAINT SKYBLUE (-9525 -5825);
FORCEPROP 1 LAST MATERIAL CHIP
J 0
(-9725 -5825);
DISPLAY 0.510638 (-9725 -5825);
PAINT SKYBLUE (-9725 -5825);
FORCEPROP 1 LAST TOLERANCE 1%
J 0
(-9625 -5750);
DISPLAY 0.510638 (-9625 -5750);
PAINT SKYBLUE (-9625 -5750);
DISPLAY INVISIBLE (-9625 -5750);
FORCEPROP 1 LAST PART_NUMBER CS03322FB03
J 0
(-10150 -5700);
DISPLAY 0.510638 (-10150 -5700);
PAINT WHITE (-10150 -5700);
DISPLAY INVISIBLE (-10150 -5700);
FORCEPROP 1 LAST PACK_TYPE 0402LF
J 0
(-10000 -5750);
DISPLAY 0.510638 (-10000 -5750);
PAINT SKYBLUE (-10000 -5750);
DISPLAY INVISIBLE (-10000 -5750);
FORCEPROP 1 LAST WATTAGE 1/16W
J 2
(-9650 -5750);
DISPLAY 0.510638 (-9650 -5750);
PAINT SKYBLUE (-9650 -5750);
DISPLAY INVISIBLE (-9650 -5750);
FORCEPROP 1 LAST PATH I117
J 0
(-9950 -5650);
DISPLAY 0.978723 (-9950 -5650);
PAINT WHITE (-9950 -5650);
DISPLAY INVISIBLE (-9950 -5650);
FORCEPROP 2 LAST CDS_LIB pure_quanta
J 0
(-9900 -5800);
DISPLAY INVISIBLE (-9900 -5800);
FORCEPROP 1 LAST LOCATION R33
J 0
(-10050 -5800);
DISPLAY 0.702128 (-10050 -5800);
PAINT YELLOW (-10050 -5800);
FORCEPROP 1 LASTPIN (-10000 -5800) $PN 1
J 0
(-10035 -5840);
DISPLAY 0.808511 (-10035 -5840);
PAINT WHITE (-10035 -5840);
FORCEPROP 1 LASTPIN (-9800 -5800) $PN 2
J 0
(-9810 -5840);
DISPLAY 0.808511 (-9810 -5840);
PAINT WHITE (-9810 -5840);
FORCEPROP 0 LAST $SEC 1
J 0
(-9450 -5750);
DISPLAY 0.680851 (-9450 -5750);
PAINT MONO (-9450 -5750);
DISPLAY INVISIBLE (-9450 -5750);
FORCEPROP 0 LAST CDS_SEC 1
J 0
(-9450 -5750);
DISPLAY 1.021277 (-9450 -5750);
DISPLAY INVISIBLE (-9450 -5750);
FORCEADD Q_RES..1
R 2
(-9900 -5700);
FORCEPROP 1 LAST PACK_TYPE 0402LF
J 2
(-9300 -5725);
DISPLAY 0.510638 (-9300 -5725);
PAINT SKYBLUE (-9300 -5725);
FORCEPROP 1 LAST MATERIAL CHIP
J 2
(-9625 -5725);
DISPLAY 0.510638 (-9625 -5725);
PAINT SKYBLUE (-9625 -5725);
FORCEPROP 1 LAST WATTAGE 1/16W
J 0
(-9600 -5725);
DISPLAY 0.510638 (-9600 -5725);
PAINT SKYBLUE (-9600 -5725);
FORCEPROP 1 LAST TOLERANCE 5%
J 2
(-9750 -5725);
DISPLAY 0.510638 (-9750 -5725);
PAINT SKYBLUE (-9750 -5725);
FORCEPROP 1 LAST VALUE 0
J 0
(-9850 -5725);
DISPLAY 0.510638 (-9850 -5725);
PAINT SKYBLUE (-9850 -5725);
FORCEPROP 1 LAST PART_NUMBER CS00002JB13
J 2
(-9650 -5675);
DISPLAY 0.510638 (-9650 -5675);
PAINT WHITE (-9650 -5675);
DISPLAY INVISIBLE (-9650 -5675);
FORCEPROP 1 LAST PATH I119
J 2
(-9850 -5550);
DISPLAY 0.978723 (-9850 -5550);
PAINT WHITE (-9850 -5550);
DISPLAY INVISIBLE (-9850 -5550);
FORCEPROP 2 LAST CDS_LIB pure_quanta
J 0
(-9900 -5700);
DISPLAY INVISIBLE (-9900 -5700);
FORCEPROP 1 LAST LOCATION R98
J 2
(-9950 -5700);
DISPLAY 0.702128 (-9950 -5700);
PAINT YELLOW (-9950 -5700);
FORCEPROP 0 LAST $SEC 1
J 0
(-9950 -5650);
DISPLAY 0.680851 (-9950 -5650);
PAINT MONO (-9950 -5650);
DISPLAY INVISIBLE (-9950 -5650);
FORCEPROP 0 LAST CDS_SEC 1
J 0
(-9950 -5650);
DISPLAY 1.021277 (-9950 -5650);
DISPLAY INVISIBLE (-9950 -5650);
FORCEPROP 1 LASTPIN (-9800 -5700) $PN 1
J 2
(-9812 -5688);
DISPLAY 0.808511 (-9812 -5688);
PAINT WHITE (-9812 -5688);
DISPLAY INVISIBLE (-9812 -5688);
FORCEPROP 1 LASTPIN (-10000 -5700) $PN 2
J 2
(-9962 -5688);
DISPLAY 0.808511 (-9962 -5688);
PAINT WHITE (-9962 -5688);
DISPLAY INVISIBLE (-9962 -5688);
FORCEADD OFFPAGE..1
(-10950 -5550);
FORCEPROP 2 LAST $XR0 13 
J 0
(-11201 -5550);
DISPLAY 0.638298 (-11201 -5550);
PAINT MONO (-11201 -5550);
FORCEPROP 2 LAST CDS_LIB standard
J 0
(-10950 -5550);
DISPLAY INVISIBLE (-10950 -5550);
FORCEPROP 1 LAST OFFPAGE TRUE
J 0
(-10625 -5675);
DISPLAY 0.872340 (-10625 -5675);
PAINT GREEN (-10625 -5675);
DISPLAY INVISIBLE (-10625 -5675);
FORCEPROP 1 LAST COMMENT_BODY TRUE
J 0
(-10825 -5650);
DISPLAY 0.872340 (-10825 -5650);
PAINT PEACH (-10825 -5650);
DISPLAY INVISIBLE (-10825 -5650);
FORCEPROP 2 LAST PATH I123
J 0
(-11150 -5500);
DISPLAY 1.021277 (-11150 -5500);
DISPLAY INVISIBLE (-11150 -5500);
FORCEADD OFFPAGE..1
(-10950 -5600);
FORCEPROP 2 LAST $XR0 22 
J 0
(-11201 -5600);
DISPLAY 0.638298 (-11201 -5600);
PAINT MONO (-11201 -5600);
FORCEPROP 2 LAST CDS_LIB standard
J 0
(-10950 -5600);
DISPLAY INVISIBLE (-10950 -5600);
FORCEPROP 1 LAST OFFPAGE TRUE
J 0
(-10625 -5725);
DISPLAY 0.872340 (-10625 -5725);
PAINT GREEN (-10625 -5725);
DISPLAY INVISIBLE (-10625 -5725);
FORCEPROP 1 LAST COMMENT_BODY TRUE
J 0
(-10825 -5700);
DISPLAY 0.872340 (-10825 -5700);
PAINT PEACH (-10825 -5700);
DISPLAY INVISIBLE (-10825 -5700);
FORCEPROP 2 LAST PATH I124
J 0
(-11150 -5550);
DISPLAY 1.021277 (-11150 -5550);
DISPLAY INVISIBLE (-11150 -5550);
FORCEADD OFFPAGE..1
(-10950 -5650);
FORCEPROP 2 LAST $XR1 27 
J 0
(-11291 -5650);
DISPLAY 0.638298 (-11291 -5650);
PAINT MONO (-11291 -5650);
FORCEPROP 2 LAST $XR0 13 
J 0
(-11201 -5650);
DISPLAY 0.638298 (-11201 -5650);
PAINT MONO (-11201 -5650);
FORCEPROP 2 LAST CDS_LIB standard
J 0
(-10950 -5650);
DISPLAY INVISIBLE (-10950 -5650);
FORCEPROP 1 LAST OFFPAGE TRUE
J 0
(-10625 -5775);
DISPLAY 0.872340 (-10625 -5775);
PAINT GREEN (-10625 -5775);
DISPLAY INVISIBLE (-10625 -5775);
FORCEPROP 1 LAST COMMENT_BODY TRUE
J 0
(-10825 -5750);
DISPLAY 0.872340 (-10825 -5750);
PAINT PEACH (-10825 -5750);
DISPLAY INVISIBLE (-10825 -5750);
FORCEPROP 2 LAST PATH I125
J 0
(-11150 -5600);
DISPLAY 1.021277 (-11150 -5600);
DISPLAY INVISIBLE (-11150 -5600);
FORCEADD OFFPAGE..5
(-10950 -5700);
FORCEPROP 2 LAST $XR0 13 
J 0
(-11204 -5700);
DISPLAY 0.638298 (-11204 -5700);
PAINT MONO (-11204 -5700);
FORCEPROP 2 LAST CDS_LIB standard
J 0
(-10950 -5700);
DISPLAY INVISIBLE (-10950 -5700);
FORCEPROP 1 LAST OFFPAGE TRUE
J 0
(-10625 -5825);
DISPLAY 0.872340 (-10625 -5825);
PAINT GREEN (-10625 -5825);
DISPLAY INVISIBLE (-10625 -5825);
FORCEPROP 1 LAST COMMENT_BODY TRUE
J 0
(-10850 -5775);
DISPLAY 0.872340 (-10850 -5775);
PAINT PEACH (-10850 -5775);
DISPLAY INVISIBLE (-10850 -5775);
FORCEPROP 2 LAST PATH I126
J 0
(-11150 -5650);
DISPLAY 1.021277 (-11150 -5650);
DISPLAY INVISIBLE (-11150 -5650);
FORCEADD OFFPAGE..1
(-10950 -5750);
FORCEPROP 2 LAST $XR0 13 
J 0
(-11201 -5750);
DISPLAY 0.638298 (-11201 -5750);
PAINT MONO (-11201 -5750);
FORCEPROP 2 LAST CDS_LIB standard
J 0
(-10950 -5750);
DISPLAY INVISIBLE (-10950 -5750);
FORCEPROP 1 LAST OFFPAGE TRUE
J 0
(-10625 -5875);
DISPLAY 0.872340 (-10625 -5875);
PAINT GREEN (-10625 -5875);
DISPLAY INVISIBLE (-10625 -5875);
FORCEPROP 1 LAST COMMENT_BODY TRUE
J 0
(-10825 -5850);
DISPLAY 0.872340 (-10825 -5850);
PAINT PEACH (-10825 -5850);
DISPLAY INVISIBLE (-10825 -5850);
FORCEPROP 2 LAST PATH I127
J 0
(-11150 -5700);
DISPLAY 1.021277 (-11150 -5700);
DISPLAY INVISIBLE (-11150 -5700);
FORCEADD Q_RES..2
R 2
(-6550 -2450);
FORCEPROP 1 LAST PART_NUMBER CS31002FB08
J 2
(-6590 -2575);
DISPLAY 0.510638 (-6590 -2575);
PAINT WHITE (-6590 -2575);
FORCEPROP 1 LAST MATERIAL CHIP
J 2
(-6590 -2525);
DISPLAY 0.510638 (-6590 -2525);
PAINT SKYBLUE (-6590 -2525);
FORCEPROP 1 LAST WATTAGE 1/16W
J 2
(-6590 -2475);
DISPLAY 0.510638 (-6590 -2475);
PAINT SKYBLUE (-6590 -2475);
FORCEPROP 1 LAST PACK_TYPE 0402LF
J 2
(-6590 -2625);
DISPLAY 0.510638 (-6590 -2625);
PAINT SKYBLUE (-6590 -2625);
FORCEPROP 1 LAST TOLERANCE 1%
J 2
(-6595 -2425);
DISPLAY 0.510638 (-6595 -2425);
PAINT SKYBLUE (-6595 -2425);
FORCEPROP 1 LAST VALUE 10K
J 2
(-6595 -2375);
DISPLAY 0.510638 (-6595 -2375);
PAINT SKYBLUE (-6595 -2375);
FORCEPROP 2 LAST CDS_LIB pure_quanta
J 2
(-6550 -2450);
DISPLAY INVISIBLE (-6550 -2450);
FORCEPROP 1 LAST PATH I132
J 2
(-6600 -2275);
DISPLAY 0.978723 (-6600 -2275);
PAINT WHITE (-6600 -2275);
DISPLAY INVISIBLE (-6600 -2275);
FORCEPROP 1 LAST LOCATION R136
J 2
(-6595 -2325);
DISPLAY 0.702128 (-6595 -2325);
PAINT YELLOW (-6595 -2325);
FORCEPROP 0 LAST $SEC 1
J 2
(-6600 -2275);
DISPLAY 0.680851 (-6600 -2275);
PAINT MONO (-6600 -2275);
DISPLAY INVISIBLE (-6600 -2275);
FORCEPROP 0 LAST CDS_SEC 1
J 2
(-6600 -2275);
DISPLAY 1.021277 (-6600 -2275);
DISPLAY INVISIBLE (-6600 -2275);
FORCEPROP 1 LASTPIN (-6550 -2350) $PN 1
J 2
(-6555 -2388);
DISPLAY 0.808511 (-6555 -2388);
PAINT WHITE (-6555 -2388);
DISPLAY INVISIBLE (-6555 -2388);
FORCEPROP 1 LASTPIN (-6550 -2550) $PN 2
J 2
(-6555 -2540);
DISPLAY 0.808511 (-6555 -2540);
PAINT WHITE (-6555 -2540);
DISPLAY INVISIBLE (-6555 -2540);
FORCEADD UNIVERSAL_POWER..1
(-6550 -2075);
FORCEPROP 3 LASTPIN (-6550 -2125) SIG_NAME P3V3_AUX\g
J 0
(-6540 -2115);
DISPLAY 0.659574 (-6540 -2115);
PAINT MONO (-6540 -2115);
DISPLAY INVISIBLE (-6540 -2115);
FORCEPROP 1 LAST HDL_POWER P3V3_AUX
J 1
(-6550 -2025);
DISPLAY 0.702128 (-6550 -2025);
PAINT PEACH (-6550 -2025);
FORCEPROP 2 LAST CDS_LIB logical_power
J 0
(-6550 -2075);
DISPLAY INVISIBLE (-6550 -2075);
FORCEPROP 1 LAST PATH I133
J 0
(-6500 -2050);
DISPLAY 0.872340 (-6500 -2050);
PAINT AQUA (-6500 -2050);
DISPLAY INVISIBLE (-6500 -2050);
FORCEADD Q_RES..2
R 2
(-9000 -3250);
FORCEPROP 1 LAST WATTAGE 1/16W
J 2
(-9040 -3275);
DISPLAY 0.510638 (-9040 -3275);
PAINT SKYBLUE (-9040 -3275);
FORCEPROP 1 LAST PACK_TYPE 0402LF
J 2
(-9040 -3425);
DISPLAY 0.510638 (-9040 -3425);
PAINT SKYBLUE (-9040 -3425);
FORCEPROP 1 LAST VALUE 10K
J 2
(-9045 -3175);
DISPLAY 0.510638 (-9045 -3175);
PAINT SKYBLUE (-9045 -3175);
FORCEPROP 1 LAST MATERIAL CHIP
J 2
(-9040 -3325);
DISPLAY 0.510638 (-9040 -3325);
PAINT SKYBLUE (-9040 -3325);
FORCEPROP 1 LAST TOLERANCE 1%
J 2
(-9045 -3225);
DISPLAY 0.510638 (-9045 -3225);
PAINT SKYBLUE (-9045 -3225);
FORCEPROP 1 LAST PART_NUMBER CS31002FB08
J 2
(-9040 -3375);
DISPLAY 0.510638 (-9040 -3375);
PAINT WHITE (-9040 -3375);
FORCEPROP 1 LAST PATH I134
J 2
(-9050 -3075);
DISPLAY 0.978723 (-9050 -3075);
PAINT WHITE (-9050 -3075);
DISPLAY INVISIBLE (-9050 -3075);
FORCEPROP 2 LAST CDS_LIB pure_quanta
J 2
(-9000 -3250);
DISPLAY INVISIBLE (-9000 -3250);
FORCEPROP 1 LAST LOCATION R126
J 2
(-9045 -3125);
DISPLAY 0.702128 (-9045 -3125);
PAINT YELLOW (-9045 -3125);
FORCEPROP 0 LAST $SEC 1
J 2
(-9050 -3075);
DISPLAY 0.680851 (-9050 -3075);
PAINT MONO (-9050 -3075);
DISPLAY INVISIBLE (-9050 -3075);
FORCEPROP 0 LAST CDS_SEC 1
J 2
(-9050 -3075);
DISPLAY 1.021277 (-9050 -3075);
DISPLAY INVISIBLE (-9050 -3075);
FORCEPROP 1 LASTPIN (-9000 -3150) $PN 1
J 2
(-9005 -3188);
DISPLAY 0.808511 (-9005 -3188);
PAINT WHITE (-9005 -3188);
DISPLAY INVISIBLE (-9005 -3188);
FORCEPROP 1 LASTPIN (-9000 -3350) $PN 2
J 2
(-9005 -3340);
DISPLAY 0.808511 (-9005 -3340);
PAINT WHITE (-9005 -3340);
DISPLAY INVISIBLE (-9005 -3340);
FORCEADD UNIVERSAL_POWER..1
(-8750 -3150);
FORCEPROP 3 LASTPIN (-8750 -3200) SIG_NAME P3V3_AUX\g
J 0
(-8740 -3190);
DISPLAY 0.659574 (-8740 -3190);
PAINT MONO (-8740 -3190);
DISPLAY INVISIBLE (-8740 -3190);
FORCEPROP 1 LAST HDL_POWER P3V3_AUX
J 1
(-8750 -3100);
DISPLAY 0.702128 (-8750 -3100);
PAINT PEACH (-8750 -3100);
FORCEPROP 1 LAST PATH I135
J 0
(-8700 -3125);
DISPLAY 0.872340 (-8700 -3125);
PAINT AQUA (-8700 -3125);
DISPLAY INVISIBLE (-8700 -3125);
FORCEPROP 2 LAST CDS_LIB logical_power
J 0
(-8750 -3150);
DISPLAY INVISIBLE (-8750 -3150);
FORCEADD Q_RES..1
(-9825 -2825);
FORCEPROP 1 LAST PART_NUMBER CS02202FB02
J 0
(-9550 -2825);
DISPLAY 0.510638 (-9550 -2825);
FORCEPROP 1 LAST MATERIAL CHIP
J 0
(-9650 -2825);
DISPLAY 0.510638 (-9650 -2825);
PAINT SKYBLUE (-9650 -2825);
FORCEPROP 1 LAST VALUE 22
J 2
(-9675 -2825);
DISPLAY 0.510638 (-9675 -2825);
PAINT SKYBLUE (-9675 -2825);
FORCEPROP 2 LAST CDS_LIB pure_quanta
J 0
(-9825 -2825);
DISPLAY INVISIBLE (-9825 -2825);
FORCEPROP 1 LAST PATH I136
J 0
(-9875 -2675);
DISPLAY 0.978723 (-9875 -2675);
PAINT WHITE (-9875 -2675);
DISPLAY INVISIBLE (-9875 -2675);
FORCEPROP 1 LAST PACK_TYPE 0402LF
J 0
(-9575 -2975);
DISPLAY 0.510638 (-9575 -2975);
DISPLAY INVISIBLE (-9575 -2975);
FORCEPROP 1 LAST WATTAGE 1/16W
J 2
(-9850 -2975);
DISPLAY 0.510638 (-9850 -2975);
DISPLAY INVISIBLE (-9850 -2975);
FORCEPROP 1 LAST TOLERANCE 1%
J 0
(-9825 -2925);
DISPLAY 0.510638 (-9825 -2925);
DISPLAY INVISIBLE (-9825 -2925);
FORCEPROP 1 LAST LOCATION R499
J 0
(-10075 -2825);
DISPLAY 0.808511 (-10075 -2825);
FORCEPROP 1 LASTPIN (-9925 -2825) $PN 1
J 0
(-9913 -2813);
DISPLAY 0.787234 (-9913 -2813);
PAINT MONO (-9913 -2813);
FORCEPROP 1 LASTPIN (-9725 -2825) $PN 2
J 0
(-9763 -2813);
DISPLAY 0.787234 (-9763 -2813);
PAINT MONO (-9763 -2813);
FORCEPROP 0 LAST $SEC 1
J 0
(-10075 -2775);
DISPLAY 0.680851 (-10075 -2775);
PAINT MONO (-10075 -2775);
DISPLAY INVISIBLE (-10075 -2775);
FORCEPROP 0 LAST CDS_SEC 1
J 0
(-10075 -2775);
DISPLAY 0.680851 (-10075 -2775);
DISPLAY INVISIBLE (-10075 -2775);
FORCEADD Q_RES..1
(-9825 -2775);
FORCEPROP 1 LAST VALUE 22
J 2
(-9675 -2775);
DISPLAY 0.510638 (-9675 -2775);
PAINT SKYBLUE (-9675 -2775);
FORCEPROP 1 LAST MATERIAL CHIP
J 0
(-9650 -2775);
DISPLAY 0.510638 (-9650 -2775);
PAINT SKYBLUE (-9650 -2775);
FORCEPROP 1 LAST PART_NUMBER CS02202FB02
J 0
(-9550 -2775);
DISPLAY 0.510638 (-9550 -2775);
FORCEPROP 2 LAST CDS_LIB pure_quanta
J 0
(-9825 -2775);
DISPLAY INVISIBLE (-9825 -2775);
FORCEPROP 1 LAST PATH I137
J 0
(-9875 -2625);
DISPLAY 0.978723 (-9875 -2625);
PAINT WHITE (-9875 -2625);
DISPLAY INVISIBLE (-9875 -2625);
FORCEPROP 1 LAST PACK_TYPE 0402LF
J 0
(-9575 -2925);
DISPLAY 0.510638 (-9575 -2925);
DISPLAY INVISIBLE (-9575 -2925);
FORCEPROP 1 LAST WATTAGE 1/16W
J 2
(-9850 -2925);
DISPLAY 0.510638 (-9850 -2925);
DISPLAY INVISIBLE (-9850 -2925);
FORCEPROP 1 LAST TOLERANCE 1%
J 0
(-9825 -2875);
DISPLAY 0.510638 (-9825 -2875);
DISPLAY INVISIBLE (-9825 -2875);
FORCEPROP 1 LAST LOCATION R498
J 0
(-10075 -2775);
DISPLAY 0.808511 (-10075 -2775);
FORCEPROP 1 LASTPIN (-9925 -2775) $PN 1
J 0
(-9913 -2763);
DISPLAY 0.787234 (-9913 -2763);
PAINT MONO (-9913 -2763);
FORCEPROP 1 LASTPIN (-9725 -2775) $PN 2
J 0
(-9763 -2763);
DISPLAY 0.787234 (-9763 -2763);
PAINT MONO (-9763 -2763);
FORCEPROP 0 LAST $SEC 1
J 0
(-10075 -2725);
DISPLAY 0.680851 (-10075 -2725);
PAINT MONO (-10075 -2725);
DISPLAY INVISIBLE (-10075 -2725);
FORCEPROP 0 LAST CDS_SEC 1
J 0
(-10075 -2725);
DISPLAY 0.680851 (-10075 -2725);
DISPLAY INVISIBLE (-10075 -2725);
FORCEADD UNIVERSAL_POWER..1
(-10225 -4675);
FORCEPROP 3 LASTPIN (-10225 -4725) SIG_NAME P3V3_AUX\g
J 0
(-10215 -4715);
DISPLAY 0.659574 (-10215 -4715);
PAINT MONO (-10215 -4715);
DISPLAY INVISIBLE (-10215 -4715);
FORCEPROP 1 LAST HDL_POWER P3V3_AUX
J 1
(-10225 -4625);
DISPLAY 0.702128 (-10225 -4625);
PAINT PEACH (-10225 -4625);
FORCEPROP 2 LAST CDS_LIB logical_power
J 0
(-10225 -4675);
DISPLAY INVISIBLE (-10225 -4675);
FORCEPROP 1 LAST PATH I138
J 0
(-10175 -4650);
DISPLAY 0.872340 (-10175 -4650);
PAINT AQUA (-10175 -4650);
DISPLAY INVISIBLE (-10175 -4650);
FORCEADD Q_RES..2
(-10225 -5100);
FORCEPROP 1 LAST VALUE 4.7K
J 0
(-10200 -5050);
DISPLAY 0.510638 (-10200 -5050);
PAINT SKYBLUE (-10200 -5050);
FORCEPROP 1 LAST MATERIAL EMPTY
J 0
(-10200 -5200);
DISPLAY 0.510638 (-10200 -5200);
PAINT RED (-10200 -5200);
FORCEPROP 1 LAST PART_NUMBER CS24702FB10
J 0
(-10185 -5225);
DISPLAY 0.510638 (-10185 -5225);
PAINT WHITE (-10185 -5225);
DISPLAY INVISIBLE (-10185 -5225);
FORCEPROP 1 LAST PATH I139
J 0
(-10175 -4925);
DISPLAY 0.978723 (-10175 -4925);
PAINT WHITE (-10175 -4925);
DISPLAY INVISIBLE (-10175 -4925);
FORCEPROP 2 LAST CDS_LIB pure_quanta
J 0
(-10225 -5100);
DISPLAY INVISIBLE (-10225 -5100);
FORCEPROP 1 LAST TOLERANCE 1%
J 0
(-10200 -5100);
DISPLAY 0.510638 (-10200 -5100);
PAINT SKYBLUE (-10200 -5100);
DISPLAY INVISIBLE (-10200 -5100);
FORCEPROP 1 LAST WATTAGE 1/16W
J 0
(-10200 -5150);
DISPLAY 0.510638 (-10200 -5150);
PAINT SKYBLUE (-10200 -5150);
DISPLAY INVISIBLE (-10200 -5150);
FORCEPROP 1 LAST PACK_TYPE 0402LF
J 0
(-10200 -5225);
DISPLAY 0.510638 (-10200 -5225);
PAINT SKYBLUE (-10200 -5225);
DISPLAY INVISIBLE (-10200 -5225);
FORCEPROP 1 LAST $LOCATION R408
J 0
(-10225 -4950);
DISPLAY 0.702128 (-10225 -4950);
PAINT YELLOW (-10225 -4950);
FORCEPROP 1 LASTPIN (-10225 -5000) $PN 1
J 0
(-10220 -5038);
DISPLAY 0.787234 (-10220 -5038);
PAINT MONO (-10220 -5038);
FORCEPROP 1 LASTPIN (-10225 -5200) $PN 2
J 0
(-10220 -5190);
DISPLAY 0.787234 (-10220 -5190);
PAINT MONO (-10220 -5190);
FORCEPROP 0 LAST CDS_LOCATION R408
J 0
(-10175 -4925);
DISPLAY 0.680851 (-10175 -4925);
DISPLAY INVISIBLE (-10175 -4925);
FORCEPROP 0 LAST $SEC 1
J 0
(-10175 -4925);
DISPLAY 0.680851 (-10175 -4925);
PAINT MONO (-10175 -4925);
DISPLAY INVISIBLE (-10175 -4925);
FORCEPROP 0 LAST CDS_SEC 1
J 0
(-10175 -4925);
DISPLAY 0.680851 (-10175 -4925);
DISPLAY INVISIBLE (-10175 -4925);
FORCEADD Q_RES..2
(-10125 -5100);
FORCEPROP 1 LAST VALUE 4.7K
J 0
(-10100 -5050);
DISPLAY 0.510638 (-10100 -5050);
PAINT SKYBLUE (-10100 -5050);
FORCEPROP 1 LAST MATERIAL EMPTY
J 0
(-10100 -5200);
DISPLAY 0.510638 (-10100 -5200);
PAINT RED (-10100 -5200);
FORCEPROP 1 LAST WATTAGE 1/16W
J 0
(-10100 -5150);
DISPLAY 0.510638 (-10100 -5150);
PAINT SKYBLUE (-10100 -5150);
DISPLAY INVISIBLE (-10100 -5150);
FORCEPROP 1 LAST TOLERANCE 1%
J 0
(-10100 -5100);
DISPLAY 0.510638 (-10100 -5100);
PAINT SKYBLUE (-10100 -5100);
DISPLAY INVISIBLE (-10100 -5100);
FORCEPROP 1 LAST PACK_TYPE 0402LF
J 0
(-10100 -5225);
DISPLAY 0.510638 (-10100 -5225);
PAINT SKYBLUE (-10100 -5225);
DISPLAY INVISIBLE (-10100 -5225);
FORCEPROP 2 LAST CDS_LIB pure_quanta
J 0
(-10125 -5100);
DISPLAY INVISIBLE (-10125 -5100);
FORCEPROP 1 LAST PATH I140
J 0
(-10075 -4925);
DISPLAY 0.978723 (-10075 -4925);
PAINT WHITE (-10075 -4925);
DISPLAY INVISIBLE (-10075 -4925);
FORCEPROP 1 LAST PART_NUMBER CS24702FB10
J 0
(-10085 -5225);
DISPLAY 0.510638 (-10085 -5225);
PAINT WHITE (-10085 -5225);
DISPLAY INVISIBLE (-10085 -5225);
FORCEPROP 1 LAST $LOCATION R414
J 0
(-10125 -4950);
DISPLAY 0.787234 (-10125 -4950);
FORCEPROP 1 LASTPIN (-10125 -5000) $PN 1
J 0
(-10120 -5038);
DISPLAY 0.787234 (-10120 -5038);
PAINT MONO (-10120 -5038);
FORCEPROP 1 LASTPIN (-10125 -5200) $PN 2
J 0
(-10120 -5190);
DISPLAY 0.787234 (-10120 -5190);
PAINT MONO (-10120 -5190);
FORCEPROP 0 LAST CDS_LOCATION R414
J 0
(-10125 -4900);
DISPLAY 0.680851 (-10125 -4900);
DISPLAY INVISIBLE (-10125 -4900);
FORCEPROP 0 LAST $SEC 1
J 0
(-10125 -4900);
DISPLAY 0.680851 (-10125 -4900);
PAINT MONO (-10125 -4900);
DISPLAY INVISIBLE (-10125 -4900);
FORCEPROP 0 LAST CDS_SEC 1
J 0
(-10125 -4900);
DISPLAY 0.680851 (-10125 -4900);
DISPLAY INVISIBLE (-10125 -4900);
FORCEADD OFFPAGE..6
(-10950 -5800);
FORCEPROP 2 LAST $XR0 12 
J 0
(-11229 -5800);
DISPLAY 0.638298 (-11229 -5800);
PAINT MONO (-11229 -5800);
FORCEPROP 2 LAST $XR1 21 
J 0
(-11319 -5800);
DISPLAY 0.638298 (-11319 -5800);
PAINT MONO (-11319 -5800);
FORCEPROP 2 LAST $XR2 34 
J 0
(-11409 -5800);
DISPLAY 0.638298 (-11409 -5800);
PAINT MONO (-11409 -5800);
FORCEPROP 2 LAST $XR3 36 
J 0
(-11499 -5800);
DISPLAY 0.638298 (-11499 -5800);
PAINT MONO (-11499 -5800);
FORCEPROP 2 LAST CDS_LIB standard
J 0
(-10950 -5800);
DISPLAY INVISIBLE (-10950 -5800);
FORCEPROP 1 LAST OFFPAGE TRUE
J 0
(-10625 -5925);
DISPLAY 0.872340 (-10625 -5925);
PAINT GREEN (-10625 -5925);
DISPLAY INVISIBLE (-10625 -5925);
FORCEPROP 1 LAST COMMENT_BODY TRUE
J 0
(-10850 -5875);
DISPLAY 0.872340 (-10850 -5875);
PAINT PEACH (-10850 -5875);
DISPLAY INVISIBLE (-10850 -5875);
FORCEPROP 2 LAST PATH I141
J 0
(-11225 -5750);
DISPLAY 0.680851 (-11225 -5750);
DISPLAY INVISIBLE (-11225 -5750);
FORCEADD OFFPAGE..4
(-5425 -5700);
FORCEPROP 2 LAST $XR3 36 
J 0
(-4969 -5700);
DISPLAY 0.638298 (-4969 -5700);
PAINT MONO (-4969 -5700);
FORCEPROP 2 LAST $XR2 34 
J 0
(-5059 -5700);
DISPLAY 0.638298 (-5059 -5700);
PAINT MONO (-5059 -5700);
FORCEPROP 2 LAST $XR1 21 
J 0
(-5149 -5700);
DISPLAY 0.638298 (-5149 -5700);
PAINT MONO (-5149 -5700);
FORCEPROP 2 LAST $XR0 12 
J 0
(-5239 -5700);
DISPLAY 0.638298 (-5239 -5700);
PAINT MONO (-5239 -5700);
FORCEPROP 2 LAST PATH I143
J 0
(-4825 -5650);
DISPLAY 0.680851 (-4825 -5650);
DISPLAY INVISIBLE (-4825 -5650);
FORCEPROP 2 LAST CDS_LIB standard
J 0
(-5425 -5700);
DISPLAY INVISIBLE (-5425 -5700);
FORCEPROP 1 LAST OFFPAGE TRUE
J 0
(-5100 -5825);
DISPLAY 1.574468 (-5100 -5825);
PAINT GREEN (-5100 -5825);
DISPLAY INVISIBLE (-5100 -5825);
FORCEPROP 1 LAST COMMENT_BODY TRUE
J 0
(-5450 -5800);
DISPLAY 1.574468 (-5450 -5800);
PAINT PEACH (-5450 -5800);
DISPLAY INVISIBLE (-5450 -5800);
FORCEADD UNIVERSAL_POWER..1
(-6300 -5050);
FORCEPROP 3 LASTPIN (-6300 -5100) SIG_NAME P3V3_AUX\g
J 0
(-6290 -5090);
DISPLAY 0.659574 (-6290 -5090);
PAINT MONO (-6290 -5090);
DISPLAY INVISIBLE (-6290 -5090);
FORCEPROP 1 LAST HDL_POWER P3V3_AUX
J 1
(-6300 -5000);
DISPLAY 0.702128 (-6300 -5000);
PAINT PEACH (-6300 -5000);
FORCEPROP 1 LAST PATH I145
J 0
(-6250 -5025);
DISPLAY 0.872340 (-6250 -5025);
PAINT AQUA (-6250 -5025);
DISPLAY INVISIBLE (-6250 -5025);
FORCEPROP 2 LAST CDS_LIB logical_power
J 0
(-6300 -5050);
DISPLAY INVISIBLE (-6300 -5050);
FORCEADD UNIVERSAL_POWER..1
(-5250 -2000);
FORCEPROP 3 LASTPIN (-5250 -2050) SIG_NAME P3V3_AUX\g
J 0
(-5240 -2040);
DISPLAY 0.659574 (-5240 -2040);
PAINT MONO (-5240 -2040);
DISPLAY INVISIBLE (-5240 -2040);
FORCEPROP 1 LAST HDL_POWER P3V3_AUX
J 1
(-5250 -1950);
DISPLAY 0.702128 (-5250 -1950);
PAINT PEACH (-5250 -1950);
FORCEPROP 1 LAST PATH I146
J 0
(-5200 -1975);
DISPLAY 0.872340 (-5200 -1975);
PAINT AQUA (-5200 -1975);
DISPLAY INVISIBLE (-5200 -1975);
FORCEPROP 2 LAST CDS_LIB logical_power
J 0
(-5250 -2000);
DISPLAY INVISIBLE (-5250 -2000);
FORCEADD Q_RES..1
R 2
(-9900 -5750);
FORCEPROP 1 LAST MATERIAL CHIP
J 2
(-9625 -5775);
DISPLAY 0.510638 (-9625 -5775);
PAINT SKYBLUE (-9625 -5775);
FORCEPROP 1 LAST VALUE 33.2
J 0
(-9850 -5775);
DISPLAY 0.510638 (-9850 -5775);
PAINT SKYBLUE (-9850 -5775);
FORCEPROP 1 LAST WATTAGE 1/16W
J 0
(-9500 -5775);
DISPLAY 0.510638 (-9500 -5775);
PAINT SKYBLUE (-9500 -5775);
DISPLAY INVISIBLE (-9500 -5775);
FORCEPROP 1 LAST TOLERANCE 1%
J 2
(-9525 -5750);
DISPLAY 0.510638 (-9525 -5750);
PAINT SKYBLUE (-9525 -5750);
DISPLAY INVISIBLE (-9525 -5750);
FORCEPROP 1 LAST PACK_TYPE 0402LF
J 2
(-9225 -5775);
DISPLAY 0.510638 (-9225 -5775);
PAINT SKYBLUE (-9225 -5775);
DISPLAY INVISIBLE (-9225 -5775);
FORCEPROP 1 LAST PART_NUMBER CS03322FB03
J 2
(-9650 -5725);
DISPLAY 0.510638 (-9650 -5725);
PAINT WHITE (-9650 -5725);
DISPLAY INVISIBLE (-9650 -5725);
FORCEPROP 1 LAST PATH I147
J 2
(-9850 -5600);
DISPLAY 0.978723 (-9850 -5600);
PAINT WHITE (-9850 -5600);
DISPLAY INVISIBLE (-9850 -5600);
FORCEPROP 2 LAST CDS_LIB pure_quanta
J 0
(-9900 -5750);
DISPLAY INVISIBLE (-9900 -5750);
FORCEPROP 1 LAST LOCATION R100
J 2
(-9950 -5750);
DISPLAY 0.702128 (-9950 -5750);
PAINT YELLOW (-9950 -5750);
FORCEPROP 1 LASTPIN (-9800 -5750) $PN 1
J 2
(-9812 -5738);
DISPLAY 0.787234 (-9812 -5738);
PAINT MONO (-9812 -5738);
FORCEPROP 1 LASTPIN (-10000 -5750) $PN 2
J 2
(-9962 -5738);
DISPLAY 0.787234 (-9962 -5738);
PAINT MONO (-9962 -5738);
FORCEPROP 0 LAST $SEC 1
J 0
(-9950 -5700);
DISPLAY 0.680851 (-9950 -5700);
PAINT MONO (-9950 -5700);
DISPLAY INVISIBLE (-9950 -5700);
FORCEPROP 0 LAST CDS_SEC 1
J 0
(-9950 -5700);
DISPLAY 0.680851 (-9950 -5700);
DISPLAY INVISIBLE (-9950 -5700);
FORCEADD SCONN11_9192031111LF..1
(-7875 -2850);
FORCEPROP 2 LAST VALUE SCONN11_91920-31111LF
J 0
(-8000 -2225);
DISPLAY 0.510638 (-8000 -2225);
PAINT SKYBLUE (-8000 -2225);
FORCEPROP 2 LAST PART_TYPE SMLF
J 0
(-8000 -2175);
DISPLAY 0.510638 (-8000 -2175);
PAINT SKYBLUE (-8000 -2175);
FORCEPROP 1 LAST MATERIAL IO
J 0
(-8019 -2543);
DISPLAY 0.510638 (-8019 -2543);
PAINT SKYBLUE (-8019 -2543);
FORCEPROP 1 LAST PART_NUMBER DFHS11FS009
J 0
(-8019 -2416);
DISPLAY 0.510638 (-8019 -2416);
PAINT WHITE (-8019 -2416);
FORCEPROP 1 LAST PATH I56
J 0
(-7875 -2850);
DISPLAY 0.723404 (-7875 -2850);
PAINT GREEN (-7875 -2850);
DISPLAY INVISIBLE (-7875 -2850);
FORCEPROP 2 LAST CDS_LIB pure_quanta
J 0
(-7875 -2850);
DISPLAY INVISIBLE (-7875 -2850);
FORCEPROP 1 LAST NEEDS_NO_SIZE TRUE
J 0
(-7875 -2850);
DISPLAY 0.723404 (-7875 -2850);
PAINT GREEN (-7875 -2850);
DISPLAY INVISIBLE (-7875 -2850);
FORCEPROP 1 LAST CDS_LMAN_SYM_OUTLINE -150,275,150,-275
J 0
(-7875 -2850);
DISPLAY 0.468085 (-7875 -2850);
PAINT GREEN (-7875 -2850);
DISPLAY INVISIBLE (-7875 -2850);
FORCEPROP 1 LAST LOCATION J5
J 0
(-8019 -2269);
DISPLAY 0.702128 (-8019 -2269);
PAINT YELLOW (-8019 -2269);
FORCEPROP 0 LASTPIN (-8175 -2675) $PN 1
J 2
(-8185 -2665);
DISPLAY 0.680851 (-8185 -2665);
PAINT MONO (-8185 -2665);
FORCEPROP 0 LASTPIN (-8175 -2725) $PN 2
J 2
(-8185 -2715);
DISPLAY 0.680851 (-8185 -2715);
PAINT MONO (-8185 -2715);
FORCEPROP 0 LASTPIN (-8175 -2775) $PN 3
J 2
(-8185 -2765);
DISPLAY 0.680851 (-8185 -2765);
PAINT MONO (-8185 -2765);
FORCEPROP 0 LASTPIN (-8175 -2825) $PN 4
J 2
(-8185 -2815);
DISPLAY 0.680851 (-8185 -2815);
PAINT MONO (-8185 -2815);
FORCEPROP 0 LASTPIN (-8175 -2875) $PN 5
J 2
(-8185 -2865);
DISPLAY 0.680851 (-8185 -2865);
PAINT MONO (-8185 -2865);
FORCEPROP 0 LASTPIN (-8175 -2925) $PN 6
J 2
(-8185 -2915);
DISPLAY 0.680851 (-8185 -2915);
PAINT MONO (-8185 -2915);
FORCEPROP 0 LASTPIN (-7575 -2675) $PN 7
J 0
(-7565 -2665);
DISPLAY 0.680851 (-7565 -2665);
PAINT MONO (-7565 -2665);
FORCEPROP 0 LASTPIN (-7575 -2725) $PN 8
J 0
(-7565 -2715);
DISPLAY 0.680851 (-7565 -2715);
PAINT MONO (-7565 -2715);
FORCEPROP 0 LASTPIN (-7575 -2775) $PN 9
J 0
(-7565 -2765);
DISPLAY 0.680851 (-7565 -2765);
PAINT MONO (-7565 -2765);
FORCEPROP 0 LASTPIN (-7575 -2825) $PN 10
J 0
(-7565 -2815);
DISPLAY 0.680851 (-7565 -2815);
PAINT MONO (-7565 -2815);
FORCEPROP 0 LASTPIN (-7575 -2875) $PN 11
J 0
(-7565 -2865);
DISPLAY 0.680851 (-7565 -2865);
PAINT MONO (-7565 -2865);
FORCEPROP 0 LASTPIN (-7575 -2975) $PN G1
J 0
(-7565 -2965);
DISPLAY 0.680851 (-7565 -2965);
PAINT MONO (-7565 -2965);
FORCEPROP 0 LASTPIN (-7575 -3025) $PN G2
J 0
(-7565 -3015);
DISPLAY 0.680851 (-7565 -3015);
PAINT MONO (-7565 -3015);
FORCEPROP 0 LAST $SEC 1
J 0
(-8000 -2150);
DISPLAY 0.680851 (-8000 -2150);
PAINT MONO (-8000 -2150);
DISPLAY INVISIBLE (-8000 -2150);
FORCEPROP 0 LAST CDS_SEC 1
J 0
(-8000 -2150);
DISPLAY 1.021277 (-8000 -2150);
DISPLAY INVISIBLE (-8000 -2150);
FORCEADD Q_RES..1
R 2
(-9825 -2675);
FORCEPROP 1 LAST MATERIAL CHIP
J 2
(-9525 -2675);
DISPLAY 0.510638 (-9525 -2675);
PAINT SKYBLUE (-9525 -2675);
FORCEPROP 1 LAST VALUE 33.2
J 0
(-9750 -2675);
DISPLAY 0.510638 (-9750 -2675);
PAINT SKYBLUE (-9750 -2675);
FORCEPROP 2 LAST CDS_LIB pure_quanta
J 0
(-9825 -2675);
DISPLAY INVISIBLE (-9825 -2675);
FORCEPROP 2 LAST SEC_TYPE 0402LF
J 0
(-9775 -2475);
DISPLAY 0.680851 (-9775 -2475);
DISPLAY INVISIBLE (-9775 -2475);
FORCEPROP 1 LAST PATH I58
J 2
(-9775 -2525);
DISPLAY 0.978723 (-9775 -2525);
PAINT WHITE (-9775 -2525);
DISPLAY INVISIBLE (-9775 -2525);
FORCEPROP 1 LAST WATTAGE 1/16W
J 0
(-9425 -2700);
DISPLAY 0.510638 (-9425 -2700);
PAINT SKYBLUE (-9425 -2700);
DISPLAY INVISIBLE (-9425 -2700);
FORCEPROP 1 LAST TOLERANCE 1%
J 2
(-9450 -2675);
DISPLAY 0.510638 (-9450 -2675);
PAINT SKYBLUE (-9450 -2675);
DISPLAY INVISIBLE (-9450 -2675);
FORCEPROP 1 LAST PACK_TYPE 0402LF
J 2
(-9150 -2700);
DISPLAY 0.510638 (-9150 -2700);
PAINT SKYBLUE (-9150 -2700);
DISPLAY INVISIBLE (-9150 -2700);
FORCEPROP 1 LAST PART_NUMBER CS03322FB03
J 2
(-9575 -2650);
DISPLAY 0.510638 (-9575 -2650);
PAINT WHITE (-9575 -2650);
DISPLAY INVISIBLE (-9575 -2650);
FORCEPROP 1 LAST LOCATION R501
J 2
(-9975 -2675);
DISPLAY 0.702128 (-9975 -2675);
PAINT YELLOW (-9975 -2675);
FORCEPROP 1 LASTPIN (-9725 -2675) $PN 1
J 2
(-9737 -2663);
DISPLAY 0.808511 (-9737 -2663);
PAINT WHITE (-9737 -2663);
FORCEPROP 1 LASTPIN (-9925 -2675) $PN 2
J 2
(-9887 -2663);
DISPLAY 0.808511 (-9887 -2663);
PAINT WHITE (-9887 -2663);
FORCEPROP 2 LAST SEC 1
J 0
(-9775 -2475);
DISPLAY 0.680851 (-9775 -2475);
PAINT MONO (-9775 -2475);
DISPLAY INVISIBLE (-9775 -2475);
FORCEADD OFFPAGE..1
(-10825 -2725);
FORCEPROP 2 LAST $XR4 34 
J 0
(-11406 -2725);
DISPLAY 0.638298 (-11406 -2725);
PAINT MONO (-11406 -2725);
FORCEPROP 2 LAST $XR3 28 
J 0
(-11316 -2725);
DISPLAY 0.638298 (-11316 -2725);
PAINT MONO (-11316 -2725);
FORCEPROP 2 LAST $XR2 12 
J 0
(-11226 -2725);
DISPLAY 0.638298 (-11226 -2725);
PAINT MONO (-11226 -2725);
FORCEPROP 2 LAST $XR1 11 
J 0
(-11136 -2725);
DISPLAY 0.638298 (-11136 -2725);
PAINT MONO (-11136 -2725);
FORCEPROP 2 LAST $XR0 10 
J 0
(-11046 -2725);
DISPLAY 0.638298 (-11046 -2725);
PAINT MONO (-11046 -2725);
FORCEPROP 2 LAST PATH I59
J 0
(-10775 -2650);
DISPLAY 1.021277 (-10775 -2650);
DISPLAY INVISIBLE (-10775 -2650);
FORCEPROP 1 LAST COMMENT_BODY TRUE
J 0
(-10700 -2825);
DISPLAY 0.872340 (-10700 -2825);
PAINT PEACH (-10700 -2825);
DISPLAY INVISIBLE (-10700 -2825);
FORCEPROP 1 LAST OFFPAGE TRUE
J 0
(-10500 -2850);
DISPLAY 0.872340 (-10500 -2850);
PAINT GREEN (-10500 -2850);
DISPLAY INVISIBLE (-10500 -2850);
FORCEPROP 2 LAST CDS_LIB standard
J 0
(-10825 -2725);
DISPLAY INVISIBLE (-10825 -2725);
FORCEADD Q_RES..1
R 2
(-9825 -2725);
FORCEPROP 1 LAST MATERIAL CHIP
J 2
(-9575 -2725);
DISPLAY 0.510638 (-9575 -2725);
PAINT SKYBLUE (-9575 -2725);
FORCEPROP 1 LAST VALUE 0
J 0
(-9725 -2725);
DISPLAY 0.510638 (-9725 -2725);
PAINT SKYBLUE (-9725 -2725);
FORCEPROP 1 LAST PART_NUMBER CS00002JB13
J 2
(-9575 -2700);
DISPLAY 0.510638 (-9575 -2700);
PAINT WHITE (-9575 -2700);
DISPLAY INVISIBLE (-9575 -2700);
FORCEPROP 1 LAST PATH I60
J 2
(-9775 -2575);
DISPLAY 0.978723 (-9775 -2575);
PAINT WHITE (-9775 -2575);
DISPLAY INVISIBLE (-9775 -2575);
FORCEPROP 2 LAST CDS_LIB pure_quanta
J 0
(-9825 -2725);
DISPLAY INVISIBLE (-9825 -2725);
FORCEPROP 2 LAST SEC_TYPE 0402LF
J 0
(-9775 -2525);
DISPLAY 0.680851 (-9775 -2525);
DISPLAY INVISIBLE (-9775 -2525);
FORCEPROP 1 LAST TOLERANCE 5%
J 2
(-9500 -2725);
DISPLAY 0.510638 (-9500 -2725);
PAINT SKYBLUE (-9500 -2725);
DISPLAY INVISIBLE (-9500 -2725);
FORCEPROP 1 LAST WATTAGE 1/16W
J 0
(-9425 -2750);
DISPLAY 0.510638 (-9425 -2750);
PAINT SKYBLUE (-9425 -2750);
DISPLAY INVISIBLE (-9425 -2750);
FORCEPROP 1 LAST PACK_TYPE 0402LF
J 2
(-9150 -2750);
DISPLAY 0.510638 (-9150 -2750);
PAINT SKYBLUE (-9150 -2750);
DISPLAY INVISIBLE (-9150 -2750);
FORCEPROP 1 LAST LOCATION R503
J 2
(-9975 -2725);
DISPLAY 0.702128 (-9975 -2725);
PAINT YELLOW (-9975 -2725);
FORCEPROP 1 LASTPIN (-9725 -2725) $PN 1
J 2
(-9737 -2713);
DISPLAY 0.808511 (-9737 -2713);
PAINT WHITE (-9737 -2713);
FORCEPROP 1 LASTPIN (-9925 -2725) $PN 2
J 2
(-9887 -2713);
DISPLAY 0.808511 (-9887 -2713);
PAINT WHITE (-9887 -2713);
FORCEPROP 0 LAST SEC 1
J 0
(-9875 -2675);
DISPLAY 0.680851 (-9875 -2675);
PAINT MONO (-9875 -2675);
DISPLAY INVISIBLE (-9875 -2675);
FORCEADD Q_RES..1
R 2
(-9825 -2875);
FORCEPROP 1 LAST PACK_TYPE 0402LF
J 2
(-9150 -2900);
DISPLAY 0.510638 (-9150 -2900);
PAINT SKYBLUE (-9150 -2900);
FORCEPROP 1 LAST WATTAGE 1/16W
J 0
(-9425 -2900);
DISPLAY 0.510638 (-9425 -2900);
PAINT SKYBLUE (-9425 -2900);
FORCEPROP 1 LAST MATERIAL CHIP
J 2
(-9450 -2900);
DISPLAY 0.510638 (-9450 -2900);
PAINT SKYBLUE (-9450 -2900);
FORCEPROP 1 LAST VALUE 0
J 0
(-9725 -2900);
DISPLAY 0.510638 (-9725 -2900);
PAINT SKYBLUE (-9725 -2900);
FORCEPROP 1 LAST TOLERANCE 5%
J 2
(-9575 -2900);
DISPLAY 0.510638 (-9575 -2900);
PAINT SKYBLUE (-9575 -2900);
FORCEPROP 1 LAST PART_NUMBER CS00002JB13
J 2
(-9575 -2850);
DISPLAY 0.510638 (-9575 -2850);
PAINT WHITE (-9575 -2850);
DISPLAY INVISIBLE (-9575 -2850);
FORCEPROP 1 LAST PATH I65
J 2
(-9775 -2725);
DISPLAY 0.978723 (-9775 -2725);
PAINT WHITE (-9775 -2725);
DISPLAY INVISIBLE (-9775 -2725);
FORCEPROP 2 LAST CDS_LIB pure_quanta
J 0
(-9825 -2875);
DISPLAY INVISIBLE (-9825 -2875);
FORCEPROP 2 LAST SEC_TYPE 0402LF
J 0
(-9775 -2675);
DISPLAY 0.680851 (-9775 -2675);
DISPLAY INVISIBLE (-9775 -2675);
FORCEPROP 1 LAST LOCATION R500
J 2
(-9975 -2875);
DISPLAY 0.702128 (-9975 -2875);
PAINT YELLOW (-9975 -2875);
FORCEPROP 1 LASTPIN (-9725 -2875) $PN 1
J 2
(-9735 -2865);
DISPLAY 0.808511 (-9735 -2865);
PAINT WHITE (-9735 -2865);
FORCEPROP 1 LASTPIN (-9925 -2875) $PN 2
J 2
(-9887 -2863);
DISPLAY 0.808511 (-9887 -2863);
PAINT WHITE (-9887 -2863);
FORCEPROP 0 LAST SEC 1
J 0
(-9875 -2825);
DISPLAY 0.680851 (-9875 -2825);
PAINT MONO (-9875 -2825);
DISPLAY INVISIBLE (-9875 -2825);
FORCEADD OFFPAGE..1
(-10825 -2875);
FORCEPROP 2 LAST $XR0 44 
J 0
(-11076 -2875);
DISPLAY 0.638298 (-11076 -2875);
PAINT MONO (-11076 -2875);
FORCEPROP 2 LAST PATH I66
J 0
(-11075 -2825);
DISPLAY 1.021277 (-11075 -2825);
DISPLAY INVISIBLE (-11075 -2825);
FORCEPROP 1 LAST COMMENT_BODY TRUE
J 0
(-10700 -2975);
DISPLAY 0.872340 (-10700 -2975);
PAINT PEACH (-10700 -2975);
DISPLAY INVISIBLE (-10700 -2975);
FORCEPROP 1 LAST OFFPAGE TRUE
J 0
(-10500 -3000);
DISPLAY 0.872340 (-10500 -3000);
PAINT GREEN (-10500 -3000);
DISPLAY INVISIBLE (-10500 -3000);
FORCEPROP 2 LAST CDS_LIB standard
J 0
(-10825 -2875);
DISPLAY INVISIBLE (-10825 -2875);
FORCEADD Q_CAP..1
(-6800 -1550);
FORCEPROP 1 LAST PACK_TYPE 0402
J 0
(-6750 -1750);
DISPLAY 0.510638 (-6750 -1750);
PAINT SKYBLUE (-6750 -1750);
FORCEPROP 1 LAST MATERIAL X7R
J 0
(-6750 -1650);
DISPLAY 0.510638 (-6750 -1650);
PAINT SKYBLUE (-6750 -1650);
FORCEPROP 1 LAST VOLTAGE 25V
J 0
(-6750 -1550);
DISPLAY 0.510638 (-6750 -1550);
PAINT SKYBLUE (-6750 -1550);
FORCEPROP 1 LAST VALUE 0.1UF
J 0
(-6750 -1500);
DISPLAY 0.510638 (-6750 -1500);
PAINT SKYBLUE (-6750 -1500);
FORCEPROP 1 LAST PART_NUMBER CH4104K1B00
J 0
(-6750 -1700);
DISPLAY 0.510638 (-6750 -1700);
PAINT WHITE (-6750 -1700);
FORCEPROP 1 LAST TOLERANCE 10%
J 0
(-6750 -1600);
DISPLAY 0.510638 (-6750 -1600);
PAINT SKYBLUE (-6750 -1600);
FORCEPROP 1 LAST PATH I67
J 0
(-6750 -1400);
DISPLAY 0.978723 (-6750 -1400);
PAINT WHITE (-6750 -1400);
DISPLAY INVISIBLE (-6750 -1400);
FORCEPROP 2 LAST CDS_LIB pure_quanta
J 0
(-6800 -1550);
DISPLAY INVISIBLE (-6800 -1550);
FORCEPROP 1 LAST LOCATION C249
J 0
(-6750 -1450);
DISPLAY 0.702128 (-6750 -1450);
PAINT YELLOW (-6750 -1450);
FORCEPROP 0 LAST $SEC 1
J 0
(-6750 -1400);
DISPLAY 0.680851 (-6750 -1400);
PAINT MONO (-6750 -1400);
DISPLAY INVISIBLE (-6750 -1400);
FORCEPROP 0 LAST CDS_SEC 1
J 0
(-6750 -1400);
DISPLAY 1.021277 (-6750 -1400);
DISPLAY INVISIBLE (-6750 -1400);
FORCEPROP 1 LASTPIN (-6800 -1450) $PN 1
J 0
(-6790 -1470);
DISPLAY 0.808511 (-6790 -1470);
PAINT WHITE (-6790 -1470);
DISPLAY INVISIBLE (-6790 -1470);
FORCEPROP 1 LASTPIN (-6800 -1650) $PN 2
J 0
(-6790 -1670);
DISPLAY 0.808511 (-6790 -1670);
PAINT WHITE (-6790 -1670);
DISPLAY INVISIBLE (-6790 -1670);
FORCEADD UNIVERSAL_POWER..1
(-7175 -1250);
FORCEPROP 3 LASTPIN (-7175 -1300) SIG_NAME P3V3_AUX\g
J 0
(-7165 -1290);
DISPLAY 0.659574 (-7165 -1290);
PAINT MONO (-7165 -1290);
DISPLAY INVISIBLE (-7165 -1290);
FORCEPROP 1 LAST HDL_POWER P3V3_AUX
J 1
(-7175 -1200);
DISPLAY 0.702128 (-7175 -1200);
PAINT PEACH (-7175 -1200);
FORCEPROP 1 LAST PATH I68
J 0
(-7125 -1225);
DISPLAY 0.872340 (-7125 -1225);
PAINT AQUA (-7125 -1225);
DISPLAY INVISIBLE (-7125 -1225);
FORCEPROP 2 LAST CDS_LIB logical_power
J 0
(-7175 -1250);
DISPLAY INVISIBLE (-7175 -1250);
FORCEADD Q_CAP..1
(-7175 -1550);
FORCEPROP 1 LAST VALUE 10UF
J 0
(-7125 -1500);
DISPLAY 0.510638 (-7125 -1500);
PAINT SKYBLUE (-7125 -1500);
FORCEPROP 1 LAST PACK_TYPE C0402
J 0
(-7125 -1750);
DISPLAY 0.510638 (-7125 -1750);
PAINT SKYBLUE (-7125 -1750);
FORCEPROP 1 LAST PART_NUMBER CH6101MEB01
J 0
(-7125 -1700);
DISPLAY 0.510638 (-7125 -1700);
PAINT WHITE (-7125 -1700);
FORCEPROP 1 LAST TOLERANCE 20%
J 0
(-7125 -1600);
DISPLAY 0.510638 (-7125 -1600);
PAINT SKYBLUE (-7125 -1600);
FORCEPROP 1 LAST MATERIAL X6S
J 0
(-7125 -1650);
DISPLAY 0.510638 (-7125 -1650);
PAINT SKYBLUE (-7125 -1650);
FORCEPROP 1 LAST VOLTAGE 6.3V
J 0
(-7125 -1550);
DISPLAY 0.510638 (-7125 -1550);
PAINT SKYBLUE (-7125 -1550);
FORCEPROP 1 LAST PATH I69
J 0
(-7125 -1400);
DISPLAY 0.978723 (-7125 -1400);
PAINT WHITE (-7125 -1400);
DISPLAY INVISIBLE (-7125 -1400);
FORCEPROP 2 LAST CDS_LIB pure_quanta
J 0
(-7175 -1550);
DISPLAY INVISIBLE (-7175 -1550);
FORCEPROP 1 LAST LOCATION C248
J 0
(-7125 -1450);
DISPLAY 0.702128 (-7125 -1450);
PAINT YELLOW (-7125 -1450);
FORCEPROP 0 LAST $SEC 1
J 0
(-7125 -1400);
DISPLAY 0.680851 (-7125 -1400);
PAINT MONO (-7125 -1400);
DISPLAY INVISIBLE (-7125 -1400);
FORCEPROP 0 LAST CDS_SEC 1
J 0
(-7125 -1400);
DISPLAY 1.021277 (-7125 -1400);
DISPLAY INVISIBLE (-7125 -1400);
FORCEPROP 1 LASTPIN (-7175 -1450) $PN 1
J 0
(-7165 -1470);
DISPLAY 0.808511 (-7165 -1470);
PAINT WHITE (-7165 -1470);
DISPLAY INVISIBLE (-7165 -1470);
FORCEPROP 1 LASTPIN (-7175 -1650) $PN 2
J 0
(-7165 -1670);
DISPLAY 0.808511 (-7165 -1670);
PAINT WHITE (-7165 -1670);
DISPLAY INVISIBLE (-7165 -1670);
FORCEADD UNIVERSAL_GND..1
(-7175 -2000);
FORCEPROP 3 LASTPIN (-7175 -1950) SIG_NAME GND\g
J 0
(-7165 -1940);
DISPLAY 0.659574 (-7165 -1940);
PAINT MONO (-7165 -1940);
DISPLAY INVISIBLE (-7165 -1940);
FORCEPROP 1 LAST PATH I70
J 0
(-7100 -2000);
DISPLAY 0.872340 (-7100 -2000);
PAINT AQUA (-7100 -2000);
DISPLAY INVISIBLE (-7100 -2000);
FORCEPROP 1 LAST HDL_POWER GND
J 1
(-7150 -2075);
DISPLAY 0.702128 (-7150 -2075);
PAINT GREEN (-7150 -2075);
DISPLAY INVISIBLE (-7150 -2075);
FORCEPROP 2 LAST CDS_LIB logical_power
J 0
(-7175 -2000);
DISPLAY INVISIBLE (-7175 -2000);
FORCEADD UNIVERSAL_GND..1
(-7450 -3225);
FORCEPROP 3 LASTPIN (-7450 -3175) SIG_NAME GND\g
J 0
(-7440 -3165);
DISPLAY 0.659574 (-7440 -3165);
PAINT MONO (-7440 -3165);
DISPLAY INVISIBLE (-7440 -3165);
FORCEPROP 1 LAST PATH I71
J 0
(-7375 -3225);
DISPLAY 0.872340 (-7375 -3225);
PAINT AQUA (-7375 -3225);
DISPLAY INVISIBLE (-7375 -3225);
FORCEPROP 1 LAST HDL_POWER GND
J 1
(-7425 -3300);
DISPLAY 0.702128 (-7425 -3300);
PAINT GREEN (-7425 -3300);
DISPLAY INVISIBLE (-7425 -3300);
FORCEPROP 2 LAST CDS_LIB logical_power
J 0
(-7450 -3225);
DISPLAY INVISIBLE (-7450 -3225);
FORCEADD OFFPAGE..2
(-4725 -2725);
FORCEPROP 2 LAST $XR1 34 
J 0
(-4446 -2725);
DISPLAY 0.638298 (-4446 -2725);
PAINT MONO (-4446 -2725);
FORCEPROP 2 LAST $XR0 15 
J 0
(-4536 -2725);
DISPLAY 0.638298 (-4536 -2725);
PAINT MONO (-4536 -2725);
FORCEPROP 2 LAST PATH I72
J 0
(-4675 -2650);
DISPLAY 1.021277 (-4675 -2650);
DISPLAY INVISIBLE (-4675 -2650);
FORCEPROP 1 LAST COMMENT_BODY TRUE
J 0
(-4770 -2820);
DISPLAY 0.872340 (-4770 -2820);
PAINT PEACH (-4770 -2820);
DISPLAY INVISIBLE (-4770 -2820);
FORCEPROP 1 LAST OFFPAGE TRUE
J 0
(-4400 -2850);
DISPLAY 0.872340 (-4400 -2850);
PAINT GREEN (-4400 -2850);
DISPLAY INVISIBLE (-4400 -2850);
FORCEPROP 2 LAST CDS_LIB standard
J 0
(-4725 -2725);
DISPLAY INVISIBLE (-4725 -2725);
FORCEADD OFFPAGE..2
(-4725 -2775);
FORCEPROP 2 LAST $XR1 36 
J 0
(-4446 -2775);
DISPLAY 0.638298 (-4446 -2775);
PAINT MONO (-4446 -2775);
FORCEPROP 2 LAST $XR0 15 
J 0
(-4536 -2775);
DISPLAY 0.638298 (-4536 -2775);
PAINT MONO (-4536 -2775);
FORCEPROP 2 LAST PATH I73
J 0
(-4550 -2700);
DISPLAY 1.021277 (-4550 -2700);
DISPLAY INVISIBLE (-4550 -2700);
FORCEPROP 1 LAST COMMENT_BODY TRUE
J 0
(-4770 -2870);
DISPLAY 0.872340 (-4770 -2870);
PAINT PEACH (-4770 -2870);
DISPLAY INVISIBLE (-4770 -2870);
FORCEPROP 1 LAST OFFPAGE TRUE
J 0
(-4400 -2900);
DISPLAY 0.872340 (-4400 -2900);
PAINT GREEN (-4400 -2900);
DISPLAY INVISIBLE (-4400 -2900);
FORCEPROP 2 LAST CDS_LIB standard
J 0
(-4725 -2775);
DISPLAY INVISIBLE (-4725 -2775);
FORCEADD Q_RES..1
R 2
(-6275 -2775);
FORCEPROP 1 LAST MATERIAL CHIP
J 2
(-6075 -2775);
DISPLAY 0.510638 (-6075 -2775);
PAINT SKYBLUE (-6075 -2775);
FORCEPROP 1 LAST VALUE 0
J 0
(-6350 -2775);
DISPLAY 0.510638 (-6350 -2775);
PAINT SKYBLUE (-6350 -2775);
FORCEPROP 1 LAST PART_NUMBER CS00002JB13
J 2
(-6025 -2750);
DISPLAY 0.510638 (-6025 -2750);
PAINT WHITE (-6025 -2750);
DISPLAY INVISIBLE (-6025 -2750);
FORCEPROP 1 LAST PACK_TYPE 0402LF
J 2
(-5675 -2800);
DISPLAY 0.510638 (-5675 -2800);
PAINT SKYBLUE (-5675 -2800);
DISPLAY INVISIBLE (-5675 -2800);
FORCEPROP 1 LAST WATTAGE 1/16W
J 0
(-5975 -2800);
DISPLAY 0.510638 (-5975 -2800);
PAINT SKYBLUE (-5975 -2800);
DISPLAY INVISIBLE (-5975 -2800);
FORCEPROP 1 LAST PATH I74
J 2
(-6225 -2625);
DISPLAY 0.978723 (-6225 -2625);
PAINT WHITE (-6225 -2625);
DISPLAY INVISIBLE (-6225 -2625);
FORCEPROP 1 LAST TOLERANCE 5%
J 2
(-6125 -2800);
DISPLAY 0.510638 (-6125 -2800);
PAINT SKYBLUE (-6125 -2800);
DISPLAY INVISIBLE (-6125 -2800);
FORCEPROP 2 LAST CDS_LIB pure_quanta
J 0
(-6275 -2775);
DISPLAY INVISIBLE (-6275 -2775);
FORCEPROP 1 LAST LOCATION R505
J 2
(-6375 -2775);
DISPLAY 0.702128 (-6375 -2775);
PAINT YELLOW (-6375 -2775);
FORCEPROP 0 LAST $SEC 1
J 0
(-6375 -2725);
DISPLAY 0.680851 (-6375 -2725);
PAINT MONO (-6375 -2725);
DISPLAY INVISIBLE (-6375 -2725);
FORCEPROP 0 LAST CDS_SEC 1
J 0
(-6375 -2725);
DISPLAY 1.021277 (-6375 -2725);
DISPLAY INVISIBLE (-6375 -2725);
FORCEPROP 1 LASTPIN (-6175 -2775) $PN 1
J 2
(-6187 -2763);
DISPLAY 0.808511 (-6187 -2763);
PAINT WHITE (-6187 -2763);
DISPLAY INVISIBLE (-6187 -2763);
FORCEPROP 1 LASTPIN (-6375 -2775) $PN 2
J 2
(-6337 -2763);
DISPLAY 0.808511 (-6337 -2763);
PAINT WHITE (-6337 -2763);
DISPLAY INVISIBLE (-6337 -2763);
FORCEADD Q_RES..2
R 2
(-5250 -2450);
FORCEPROP 1 LAST MATERIAL CHIP
J 2
(-5290 -2525);
DISPLAY 0.510638 (-5290 -2525);
PAINT SKYBLUE (-5290 -2525);
FORCEPROP 1 LAST PART_NUMBER CS31002FB08
J 2
(-5290 -2575);
DISPLAY 0.510638 (-5290 -2575);
PAINT WHITE (-5290 -2575);
FORCEPROP 1 LAST PACK_TYPE 0402LF
J 2
(-5290 -2625);
DISPLAY 0.510638 (-5290 -2625);
PAINT SKYBLUE (-5290 -2625);
FORCEPROP 1 LAST VALUE 10K
J 2
(-5295 -2375);
DISPLAY 0.510638 (-5295 -2375);
PAINT SKYBLUE (-5295 -2375);
FORCEPROP 1 LAST TOLERANCE 1%
J 2
(-5295 -2425);
DISPLAY 0.510638 (-5295 -2425);
PAINT SKYBLUE (-5295 -2425);
FORCEPROP 1 LAST WATTAGE 1/16W
J 2
(-5290 -2475);
DISPLAY 0.510638 (-5290 -2475);
PAINT SKYBLUE (-5290 -2475);
FORCEPROP 2 LAST CDS_LIB pure_quanta
J 2
(-5250 -2450);
DISPLAY INVISIBLE (-5250 -2450);
FORCEPROP 1 LAST PATH I75
J 2
(-5300 -2275);
DISPLAY 0.978723 (-5300 -2275);
PAINT WHITE (-5300 -2275);
DISPLAY INVISIBLE (-5300 -2275);
FORCEPROP 1 LAST LOCATION R464
J 2
(-5295 -2325);
DISPLAY 0.702128 (-5295 -2325);
PAINT YELLOW (-5295 -2325);
FORCEPROP 0 LAST $SEC 1
J 2
(-5300 -2275);
DISPLAY 0.680851 (-5300 -2275);
PAINT MONO (-5300 -2275);
DISPLAY INVISIBLE (-5300 -2275);
FORCEPROP 0 LAST CDS_SEC 1
J 2
(-5300 -2275);
DISPLAY 1.021277 (-5300 -2275);
DISPLAY INVISIBLE (-5300 -2275);
FORCEPROP 1 LASTPIN (-5250 -2350) $PN 1
J 2
(-5255 -2388);
DISPLAY 0.808511 (-5255 -2388);
PAINT WHITE (-5255 -2388);
DISPLAY INVISIBLE (-5255 -2388);
FORCEPROP 1 LASTPIN (-5250 -2550) $PN 2
J 2
(-5255 -2540);
DISPLAY 0.808511 (-5255 -2540);
PAINT WHITE (-5255 -2540);
DISPLAY INVISIBLE (-5255 -2540);
FORCEADD UNIVERSAL_POWER..1
(-4875 -2000);
FORCEPROP 3 LASTPIN (-4875 -2050) SIG_NAME P3V3_AUX\g
J 0
(-4865 -2040);
DISPLAY 0.659574 (-4865 -2040);
PAINT MONO (-4865 -2040);
DISPLAY INVISIBLE (-4865 -2040);
FORCEPROP 1 LAST HDL_POWER P3V3_AUX
J 1
(-4875 -1950);
DISPLAY 0.702128 (-4875 -1950);
PAINT PEACH (-4875 -1950);
FORCEPROP 2 LAST CDS_LIB logical_power
J 0
(-4875 -2000);
DISPLAY INVISIBLE (-4875 -2000);
FORCEPROP 1 LAST PATH I77
J 0
(-4825 -1975);
DISPLAY 0.872340 (-4825 -1975);
PAINT AQUA (-4825 -1975);
DISPLAY INVISIBLE (-4825 -1975);
FORCEADD Q_RES..2
R 2
(-4875 -2475);
FORCEPROP 1 LAST WATTAGE 1/16W
J 2
(-4915 -2500);
DISPLAY 0.510638 (-4915 -2500);
PAINT SKYBLUE (-4915 -2500);
FORCEPROP 1 LAST TOLERANCE 1%
J 2
(-4920 -2450);
DISPLAY 0.510638 (-4920 -2450);
PAINT SKYBLUE (-4920 -2450);
FORCEPROP 1 LAST VALUE 10K
J 2
(-4920 -2400);
DISPLAY 0.510638 (-4920 -2400);
PAINT SKYBLUE (-4920 -2400);
FORCEPROP 1 LAST PACK_TYPE 0402LF
J 2
(-4915 -2650);
DISPLAY 0.510638 (-4915 -2650);
PAINT SKYBLUE (-4915 -2650);
FORCEPROP 1 LAST MATERIAL CHIP
J 2
(-4915 -2550);
DISPLAY 0.510638 (-4915 -2550);
PAINT SKYBLUE (-4915 -2550);
FORCEPROP 1 LAST PART_NUMBER CS31002FB08
J 2
(-4915 -2600);
DISPLAY 0.510638 (-4915 -2600);
PAINT WHITE (-4915 -2600);
FORCEPROP 2 LAST CDS_LIB pure_quanta
J 2
(-4875 -2475);
DISPLAY INVISIBLE (-4875 -2475);
FORCEPROP 1 LAST PATH I78
J 2
(-4925 -2300);
DISPLAY 0.978723 (-4925 -2300);
PAINT WHITE (-4925 -2300);
DISPLAY INVISIBLE (-4925 -2300);
FORCEPROP 1 LAST LOCATION R497
J 2
(-4920 -2350);
DISPLAY 0.702128 (-4920 -2350);
PAINT YELLOW (-4920 -2350);
FORCEPROP 0 LAST $SEC 1
J 2
(-4925 -2300);
DISPLAY 0.680851 (-4925 -2300);
PAINT MONO (-4925 -2300);
DISPLAY INVISIBLE (-4925 -2300);
FORCEPROP 0 LAST CDS_SEC 1
J 2
(-4925 -2300);
DISPLAY 1.021277 (-4925 -2300);
DISPLAY INVISIBLE (-4925 -2300);
FORCEPROP 1 LASTPIN (-4875 -2375) $PN 1
J 2
(-4880 -2413);
DISPLAY 0.808511 (-4880 -2413);
PAINT WHITE (-4880 -2413);
DISPLAY INVISIBLE (-4880 -2413);
FORCEPROP 1 LASTPIN (-4875 -2575) $PN 2
J 2
(-4880 -2565);
DISPLAY 0.808511 (-4880 -2565);
PAINT WHITE (-4880 -2565);
DISPLAY INVISIBLE (-4880 -2565);
FORCEADD OFFPAGE..1
(-10825 -2675);
FORCEPROP 2 LAST $XR1 44 
J 0
(-11136 -2675);
DISPLAY 0.638298 (-11136 -2675);
PAINT MONO (-11136 -2675);
FORCEPROP 2 LAST $XR0 10 
J 0
(-11046 -2675);
DISPLAY 0.638298 (-11046 -2675);
PAINT MONO (-11046 -2675);
FORCEPROP 2 LAST PATH I81
J 0
(-11025 -2625);
DISPLAY 1.021277 (-11025 -2625);
DISPLAY INVISIBLE (-11025 -2625);
FORCEPROP 1 LAST COMMENT_BODY TRUE
J 0
(-10700 -2775);
DISPLAY 0.872340 (-10700 -2775);
PAINT PEACH (-10700 -2775);
DISPLAY INVISIBLE (-10700 -2775);
FORCEPROP 1 LAST OFFPAGE TRUE
J 0
(-10500 -2800);
DISPLAY 0.872340 (-10500 -2800);
PAINT GREEN (-10500 -2800);
DISPLAY INVISIBLE (-10500 -2800);
FORCEPROP 2 LAST CDS_LIB standard
J 0
(-10825 -2675);
DISPLAY INVISIBLE (-10825 -2675);
FORCEADD OFFPAGE..1
(-10825 -2775);
FORCEPROP 2 LAST $XR1 44 
J 0
(-11136 -2775);
DISPLAY 0.638298 (-11136 -2775);
PAINT MONO (-11136 -2775);
FORCEPROP 2 LAST $XR0 10 
J 0
(-11046 -2775);
DISPLAY 0.638298 (-11046 -2775);
PAINT MONO (-11046 -2775);
FORCEPROP 2 LAST PATH I82
J 0
(-11025 -2725);
DISPLAY 1.021277 (-11025 -2725);
DISPLAY INVISIBLE (-11025 -2725);
FORCEPROP 1 LAST COMMENT_BODY TRUE
J 0
(-10700 -2875);
DISPLAY 0.872340 (-10700 -2875);
PAINT PEACH (-10700 -2875);
DISPLAY INVISIBLE (-10700 -2875);
FORCEPROP 1 LAST OFFPAGE TRUE
J 0
(-10500 -2900);
DISPLAY 0.872340 (-10500 -2900);
PAINT GREEN (-10500 -2900);
DISPLAY INVISIBLE (-10500 -2900);
FORCEPROP 2 LAST CDS_LIB standard
J 0
(-10825 -2775);
DISPLAY INVISIBLE (-10825 -2775);
FORCEADD OFFPAGE..5
(-10825 -2825);
FORCEPROP 2 LAST $XR1 10 
J 0
(-11169 -2825);
DISPLAY 0.638298 (-11169 -2825);
PAINT MONO (-11169 -2825);
FORCEPROP 2 LAST $XR0 44 
J 0
(-11079 -2825);
DISPLAY 0.638298 (-11079 -2825);
PAINT MONO (-11079 -2825);
FORCEPROP 2 LAST PATH I83
J 0
(-11025 -2775);
DISPLAY 1.021277 (-11025 -2775);
DISPLAY INVISIBLE (-11025 -2775);
FORCEPROP 1 LAST COMMENT_BODY TRUE
J 0
(-10725 -2900);
DISPLAY 0.872340 (-10725 -2900);
PAINT PEACH (-10725 -2900);
DISPLAY INVISIBLE (-10725 -2900);
FORCEPROP 1 LAST OFFPAGE TRUE
J 0
(-10500 -2950);
DISPLAY 0.872340 (-10500 -2950);
PAINT GREEN (-10500 -2950);
DISPLAY INVISIBLE (-10500 -2950);
FORCEPROP 2 LAST CDS_LIB standard
J 0
(-10825 -2825);
DISPLAY INVISIBLE (-10825 -2825);
FORCEADD UNIVERSAL_POWER..1
(-5625 -5050);
FORCEPROP 3 LASTPIN (-5625 -5100) SIG_NAME P3V3_AUX\g
J 0
(-5615 -5090);
DISPLAY 0.659574 (-5615 -5090);
PAINT MONO (-5615 -5090);
DISPLAY INVISIBLE (-5615 -5090);
FORCEPROP 1 LAST HDL_POWER P3V3_AUX
J 1
(-5625 -5000);
DISPLAY 0.702128 (-5625 -5000);
PAINT PEACH (-5625 -5000);
FORCEPROP 1 LAST PATH I97
J 0
(-5575 -5025);
DISPLAY 0.872340 (-5575 -5025);
PAINT AQUA (-5575 -5025);
DISPLAY INVISIBLE (-5575 -5025);
FORCEPROP 2 LAST CDS_LIB logical_power
J 0
(-5625 -5050);
DISPLAY INVISIBLE (-5625 -5050);
FORCEADD Q_RES..2
R 2
(-5625 -5400);
FORCEPROP 1 LAST VALUE 10K
J 2
(-5670 -5325);
DISPLAY 0.510638 (-5670 -5325);
PAINT SKYBLUE (-5670 -5325);
FORCEPROP 1 LAST TOLERANCE 1%
J 2
(-5670 -5375);
DISPLAY 0.510638 (-5670 -5375);
PAINT SKYBLUE (-5670 -5375);
FORCEPROP 1 LAST WATTAGE 1/16W
J 2
(-5665 -5425);
DISPLAY 0.510638 (-5665 -5425);
PAINT SKYBLUE (-5665 -5425);
FORCEPROP 1 LAST MATERIAL CHIP
J 2
(-5665 -5475);
DISPLAY 0.510638 (-5665 -5475);
PAINT SKYBLUE (-5665 -5475);
FORCEPROP 1 LAST PART_NUMBER CS31002FB08
J 2
(-5665 -5525);
DISPLAY 0.510638 (-5665 -5525);
PAINT WHITE (-5665 -5525);
FORCEPROP 1 LAST PACK_TYPE 0402LF
J 2
(-5665 -5575);
DISPLAY 0.510638 (-5665 -5575);
PAINT SKYBLUE (-5665 -5575);
FORCEPROP 2 LAST CDS_LIB pure_quanta
J 2
(-5625 -5400);
DISPLAY INVISIBLE (-5625 -5400);
FORCEPROP 1 LAST PATH I98
J 2
(-5675 -5225);
DISPLAY 0.978723 (-5675 -5225);
PAINT WHITE (-5675 -5225);
DISPLAY INVISIBLE (-5675 -5225);
FORCEPROP 1 LAST LOCATION R59
J 2
(-5670 -5275);
DISPLAY 0.702128 (-5670 -5275);
PAINT YELLOW (-5670 -5275);
FORCEPROP 0 LAST $SEC 1
J 2
(-5675 -5225);
DISPLAY 0.680851 (-5675 -5225);
PAINT MONO (-5675 -5225);
DISPLAY INVISIBLE (-5675 -5225);
FORCEPROP 0 LAST CDS_SEC 1
J 2
(-5675 -5225);
DISPLAY 1.021277 (-5675 -5225);
DISPLAY INVISIBLE (-5675 -5225);
FORCEPROP 1 LASTPIN (-5625 -5300) $PN 1
J 2
(-5630 -5338);
DISPLAY 0.808511 (-5630 -5338);
PAINT WHITE (-5630 -5338);
DISPLAY INVISIBLE (-5630 -5338);
FORCEPROP 1 LASTPIN (-5625 -5500) $PN 2
J 2
(-5630 -5490);
DISPLAY 0.808511 (-5630 -5490);
PAINT WHITE (-5630 -5490);
DISPLAY INVISIBLE (-5630 -5490);
FORCEADD OFFPAGE..2
(-5425 -5650);
FORCEPROP 2 LAST $XR0 13 
J 0
(-5236 -5650);
DISPLAY 0.638298 (-5236 -5650);
PAINT MONO (-5236 -5650);
FORCEPROP 2 LAST CDS_LIB standard
J 0
(-5425 -5650);
DISPLAY INVISIBLE (-5425 -5650);
FORCEPROP 1 LAST OFFPAGE TRUE
J 0
(-5100 -5775);
DISPLAY 0.872340 (-5100 -5775);
PAINT GREEN (-5100 -5775);
DISPLAY INVISIBLE (-5100 -5775);
FORCEPROP 1 LAST COMMENT_BODY TRUE
J 0
(-5470 -5745);
DISPLAY 0.872340 (-5470 -5745);
PAINT PEACH (-5470 -5745);
DISPLAY INVISIBLE (-5470 -5745);
FORCEPROP 2 LAST PATH I99
J 0
(-5125 -5600);
DISPLAY 1.021277 (-5125 -5600);
DISPLAY INVISIBLE (-5125 -5600);
FORCEADD QUANTA_TITLE_BLOCK_C..1
(-3750 -7475);
FORCEPROP 0 LAST CDS_CON_LAST_MODIFIED Fri Aug 25 17:25:47 2023
J 0
(-5635 -7460);
DISPLAY INVISIBLE (-5635 -7460);
FORCEPROP 2 LAST Q_DEPT 
J 1
(-7513 -7426);
DISPLAY 1.957447 (-7513 -7426);
PAINT GREEN (-7513 -7426);
FORCEPROP 1 LAST CUSTOM_TXT_CDS <CON_LAST_MODIFIED>
J 0
(-5635 -7460);
DISPLAY 0.978723 (-5635 -7460);
FORCEPROP 2 LAST CUSTOM_TXT_CDS <XR_PAGE_TITLE>
J 0
(-11640 -2225);
DISPLAY 0.638298 (-11640 -2225);
PAINT PINK (-11640 -2225);
DISPLAY INVISIBLE (-11640 -2225);
FORCEPROP 1 LAST CUSTOM_TXT_CDS <NAME_2>
J 0
(-6925 -7425);
FORCEPROP 1 LAST CUSTOM_TXT_CDS <NAME_1>
J 0
(-6925 -7300);
FORCEPROP 1 LAST CUSTOM_TXT_CDS <Q_NUMBER>
J 0
(-5153 -7372);
DISPLAY 1.212766 (-5153 -7372);
FORCEPROP 1 LAST CUSTOM_TXT_CDS <Q_PROJ>
J 0
(-6132 -7373);
DISPLAY 1.212766 (-6132 -7373);
FORCEPROP 1 LAST CUSTOM_TXT_CDS <Q_REV>
J 0
(-3934 -7372);
DISPLAY 1.212766 (-3934 -7372);
FORCEPROP 1 LAST CUSTOM_TXT_CDS <CON_PAGE_NUM> OF <CON_TOTAL_PAGES>
J 0
(-4196 -7457);
DISPLAY 0.978723 (-4196 -7457);
FORCEPROP 1 LAST Q_TITLE TPM2.0 CONN
J 0
(-13016 -7374);
DISPLAY 2.446809 (-13016 -7374);
PAINT GREEN (-13016 -7374);
FORCEPROP 1 LAST COMMENT_BODY TRUE
J 0
(-3738 -7488);
DISPLAY 0.978723 (-3738 -7488);
PAINT PEACH (-3738 -7488);
DISPLAY INVISIBLE (-3738 -7488);
FORCEPROP 1 LAST CDS_LMAN_SYM_OUTLINE -9475,6775,100,-125
J 0
(-3750 -7475);
DISPLAY 0.468085 (-3750 -7475);
PAINT GREEN (-3750 -7475);
DISPLAY INVISIBLE (-3750 -7475);
FORCEPROP 2 LAST CDS_LIB pure_quanta
J 0
(-3750 -7475);
DISPLAY INVISIBLE (-3750 -7475);
FORCEPROP 2 LAST PAGE_BORDER TRUE
J 0
(-11640 -2225);
DISPLAY 0.638298 (-11640 -2225);
PAINT PINK (-11640 -2225);
DISPLAY INVISIBLE (-11640 -2225);
FORCEPROP 2 LAST CDS_XR_PAGE_TITLE CR-46 : @SCM_LIB.SCM(SCH_1):PAGE46
J 0
(-11640 -2225);
DISPLAY 0.638298 (-11640 -2225);
PAINT PINK (-11640 -2225);
DISPLAY INVISIBLE (-11640 -2225);
FORCEADD DNS..1
(-10150 -5100);
PAINT RED (-10150 -5100);
FORCEPROP 2 LAST CDS_LIB mstr_misc
J 0
(-10150 -5100);
DISPLAY INVISIBLE (-10150 -5100);
FORCEPROP 1 LAST COMMENT_BODY TRUE
R 1
J 0
(-10075 -5325);
DISPLAY 0.872340 (-10075 -5325);
PAINT PEACH (-10075 -5325);
DISPLAY INVISIBLE (-10075 -5325);
WIRE 16 -1 (-10225 -4875)(-10225 -4725);
WIRE 16 -1 (-10225 -4875)(-10125 -4875);
WIRE 16 -1 (-10225 -5000)(-10225 -4875);
WIRE 16 -1 (-5625 -5100)(-5625 -5300);
WIRE 16 -1 (-6300 -5100)(-6300 -5225);
WIRE 16 -1 (-6550 -2350)(-6550 -2125);
WIRE 16 -1 (-5250 -2050)(-5250 -2350);
WIRE 16 -1 (-4875 -2050)(-4875 -2375);
WIRE 16 -1 (-7175 -1300)(-7175 -1375);
WIRE 16 -1 (-8750 -3425)(-8750 -3200);
WIRE 16 -1 (-9000 -3425)(-8750 -3425);
WIRE 16 -1 (-7250 -4175)(-7250 -4250);
WIRE 16 -1 (-7250 -4825)(-7250 -4700);
WIRE 16 -1 (-7525 -5900)(-7525 -6050);
WIRE 16 -1 (-7525 -5850)(-7525 -5900);
WIRE 16 -1 (-7650 -5900)(-7525 -5900);
WIRE 16 -1 (-7175 -1950)(-7175 -1825);
WIRE 16 -1 (-7450 -3025)(-7450 -3175);
WIRE 16 -1 (-7450 -2975)(-7450 -3025);
WIRE 16 -1 (-7575 -3025)(-7450 -3025);
WIRE 16 -1 (-7650 -5750)(-7525 -5750);
WIRE 16 -1 (-7650 -5850)(-7525 -5850);
WIRE 16 -1 (-7525 -5750)(-7525 -5850);
WIRE 16 -1 (-7575 -2975)(-7450 -2975);
WIRE 16 -1 (-7450 -2875)(-7450 -2975);
WIRE 16 -1 (-7575 -2875)(-7450 -2875);
WIRE 16 -1 (-10900 -5550)(-10225 -5550);
FORCEPROP 2 LAST SIG_NAME SPI_BMC_TPM_CLK
J 2
(-10310 -5540);
DISPLAY 0.808511 (-10310 -5540);
WIRE 16 -1 (-10225 -5200)(-10225 -5550);
WIRE 16 -1 (-10000 -5550)(-10225 -5550);
WIRE 16 -1 (-10900 -5700)(-10125 -5700);
FORCEPROP 2 LAST SIG_NAME SPI_BMC_TPM_MISO
J 2
(-10285 -5690);
DISPLAY 0.808511 (-10285 -5690);
WIRE 16 -1 (-10125 -5700)(-10000 -5700);
WIRE 16 -1 (-10125 -5200)(-10125 -5700);
WIRE 16 -1 (-9800 -5650)(-8250 -5650);
FORCEPROP 2 LAST SIG_NAME SPI_BMC_TPM_MOSI_R
J 0
(-9125 -5640);
DISPLAY 0.808511 (-9125 -5640);
WIRE 16 -1 (-9800 -5750)(-8250 -5750);
FORCEPROP 2 LAST SIG_NAME SPI_BMC_TPM_CS2_N_R
J 0
(-9125 -5740);
DISPLAY 0.808511 (-9125 -5740);
WIRE 16 -1 (-9800 -5800)(-8250 -5800);
FORCEPROP 2 LAST SIG_NAME SMB_BMC_TPM_MM16_SDA
J 0
(-9135 -5790);
DISPLAY 0.808511 (-9135 -5790);
WIRE 16 -1 (-10900 -5750)(-10000 -5750);
FORCEPROP 2 LAST SIG_NAME SPI_BMC_TPM_CS2_R_N
J 0
(-10885 -5740);
DISPLAY 0.808511 (-10885 -5740);
WIRE 16 -1 (-9800 -5550)(-8250 -5550);
FORCEPROP 2 LAST SIG_NAME SPI_BMC_TPM_CLK_R
J 0
(-9125 -5540);
DISPLAY 0.808511 (-9125 -5540);
WIRE 16 -1 (-10775 -2875)(-9925 -2875);
FORCEPROP 2 LAST SIG_NAME SPI_TPM_CS_R_N
J 0
(-10775 -2865);
DISPLAY 0.808511 (-10775 -2865);
WIRE 16 -1 (-9725 -2875)(-8175 -2875);
FORCEPROP 2 LAST SIG_NAME SPI_TPM_CS_N_R
J 2
(-8300 -2865);
DISPLAY 0.808511 (-8300 -2865);
WIRE 16 -1 (-9800 -5600)(-8250 -5600);
FORCEPROP 2 LAST SIG_NAME RST_BMC_EXTRST_R3_N
J 0
(-9135 -5590);
DISPLAY 0.808511 (-9135 -5590);
WIRE 16 -1 (-10900 -5650)(-10000 -5650);
FORCEPROP 2 LAST SIG_NAME SPI_BMC_TPM_MOSI
J 2
(-10285 -5640);
DISPLAY 0.808511 (-10285 -5640);
WIRE 16 -1 (-10000 -5600)(-10900 -5600);
FORCEPROP 2 LAST SIG_NAME RST_BMC_EXTRST_R2_N
J 0
(-10885 -5590);
DISPLAY 0.808511 (-10885 -5590);
WIRE 16 -1 (-10900 -5800)(-10000 -5800);
FORCEPROP 2 LAST SIG_NAME SMB_BMC_MM16_R5_SDA
J 0
(-10885 -5790);
DISPLAY 0.808511 (-10885 -5790);
WIRE 16 -1 (-7500 -5550)(-7650 -5550);
WIRE 16 -1 (-7500 -4250)(-7500 -5550);
WIRE 16 -1 (-7250 -4325)(-7250 -4250);
WIRE 16 -1 (-7250 -4250)(-7500 -4250);
WIRE 16 -1 (-7250 -4250)(-6875 -4250);
WIRE 16 -1 (-6875 -4250)(-6875 -4325);
WIRE 16 -1 (-9800 -5700)(-8250 -5700);
FORCEPROP 2 LAST SIG_NAME SPI_BMC_TPM_MISO_R
J 0
(-9125 -5690);
DISPLAY 0.808511 (-9125 -5690);
WIRE 16 -1 (-5250 -2550)(-5250 -2725);
WIRE 16 -1 (-5250 -2725)(-4775 -2725);
WIRE 16 -1 (-7575 -2725)(-5250 -2725);
FORCEPROP 0 LAST SIG_NAME FM_TPM_PRSNT_0_N
J 2
(-5460 -2715);
DISPLAY 0.808511 (-5460 -2715);
WIRE 16 -1 (-7650 -5700)(-6700 -5700);
FORCEPROP 2 LAST SIG_NAME SMB_BMC_TPM_MM16_SCL
J 0
(-7540 -5700);
DISPLAY 0.808511 (-7540 -5700);
WIRE 16 -1 (-7650 -5650)(-6700 -5650);
FORCEPROP 0 LAST SIG_NAME IRQ_BMC_TPM_SPI_R_N
J 2
(-6830 -5650);
DISPLAY 0.808511 (-6830 -5650);
WIRE 16 -1 (-6300 -5425)(-6300 -5600);
WIRE 16 -1 (-6300 -5600)(-5475 -5600);
WIRE 16 -1 (-7650 -5600)(-6300 -5600);
FORCEPROP 0 LAST SIG_NAME FM_TPM_PRSNT_1_N
J 2
(-6935 -5590);
DISPLAY 0.808511 (-6935 -5590);
WIRE 16 -1 (-5625 -5650)(-5475 -5650);
WIRE 16 -1 (-5625 -5500)(-5625 -5650);
FORCEPROP 0 LAST SIG_NAME IRQ_TPM_SPI_N
J 2
(-5785 -5640);
DISPLAY 0.808511 (-5785 -5640);
WIRE 16 -1 (-6500 -5650)(-5625 -5650);
WIRE 16 -1 (-6500 -5700)(-5475 -5700);
FORCEPROP 2 LAST SIG_NAME SMB_BMC_MM16_R5_SCL
J 0
(-6260 -5690);
DISPLAY 0.808511 (-6260 -5690);
WIRE 16 -1 (-6875 -4525)(-6875 -4700);
WIRE 16 -1 (-7250 -4700)(-7250 -4525);
WIRE 16 -1 (-6875 -4700)(-7250 -4700);
WIRE 16 -1 (-4875 -2575)(-4875 -2775);
WIRE 16 -1 (-4875 -2775)(-4775 -2775);
WIRE 16 -1 (-6175 -2775)(-4875 -2775);
FORCEPROP 2 LAST SIG_NAME IRQ_PCH_TPM_SPI_N
J 0
(-6060 -2765);
DISPLAY 0.851064 (-6060 -2765);
WIRE 16 -1 (-7575 -2775)(-6375 -2775);
FORCEPROP 0 LAST SIG_NAME IRQ_PCH_TPM_SPI_R_N
J 0
(-7410 -2765);
DISPLAY 0.851064 (-7410 -2765);
WIRE 16 -1 (-6550 -2825)(-7575 -2825);
FORCEPROP 2 LAST SIG_NAME SMB_PCH_TPM_SCL
J 0
(-7410 -2815);
DISPLAY 0.808511 (-7410 -2815);
WIRE 16 -1 (-6550 -2825)(-6550 -2550);
WIRE 16 -1 (-7425 -2675)(-7575 -2675);
WIRE 16 -1 (-7425 -1375)(-7425 -2675);
WIRE 16 -1 (-7175 -1375)(-7175 -1450);
WIRE 16 -1 (-7175 -1375)(-7425 -1375);
WIRE 16 -1 (-7175 -1375)(-6800 -1375);
WIRE 16 -1 (-6800 -1375)(-6800 -1450);
WIRE 16 -1 (-6800 -1650)(-6800 -1825);
WIRE 16 -1 (-7175 -1825)(-7175 -1650);
WIRE 16 -1 (-6800 -1825)(-7175 -1825);
WIRE 16 -1 (-9725 -2675)(-8175 -2675);
FORCEPROP 2 LAST SIG_NAME SPI_SYS_R1_CLK
J 2
(-8300 -2665);
DISPLAY 0.808511 (-8300 -2665);
WIRE 16 -1 (-9725 -2725)(-8175 -2725);
FORCEPROP 2 LAST SIG_NAME RST_PLTRST_TPM_N
J 2
(-8300 -2715);
DISPLAY 0.808511 (-8300 -2715);
WIRE 16 -1 (-10775 -2775)(-9925 -2775);
FORCEPROP 2 LAST SIG_NAME SPI_SYS_R_MOSI
J 0
(-10775 -2765);
DISPLAY 0.808511 (-10775 -2765);
WIRE 16 -1 (-9925 -2725)(-10775 -2725);
FORCEPROP 2 LAST SIG_NAME RST_PLTRST_N
J 0
(-10775 -2715);
DISPLAY 0.808511 (-10775 -2715);
WIRE 16 -1 (-9725 -2775)(-8175 -2775);
FORCEPROP 2 LAST SIG_NAME SPI_SYS_R1_MOSI
J 2
(-8300 -2765);
DISPLAY 0.808511 (-8300 -2765);
WIRE 16 -1 (-9725 -2825)(-8175 -2825);
FORCEPROP 2 LAST SIG_NAME SPI_SYS_R1_MISO
J 2
(-8300 -2815);
DISPLAY 0.808511 (-8300 -2815);
WIRE 16 -1 (-10775 -2675)(-9925 -2675);
FORCEPROP 2 LAST SIG_NAME SPI_SYS_R_CLK
J 0
(-10775 -2665);
DISPLAY 0.808511 (-10775 -2665);
WIRE 16 -1 (-10775 -2825)(-9925 -2825);
FORCEPROP 2 LAST SIG_NAME SPI_SYS_R_MISO
J 0
(-10775 -2815);
DISPLAY 0.808511 (-10775 -2815);
WIRE 16 -1 (-9000 -3350)(-9000 -3425);
WIRE 16 -1 (-9000 -3150)(-9000 -2925);
WIRE 16 -1 (-9000 -2925)(-8175 -2925);
FORCEPROP 2 LAST SIG_NAME SMB_PCH_TPM_SDA
J 2
(-8300 -2915);
DISPLAY 0.808511 (-8300 -2915);
WIRE 16 -1 (-10125 -5000)(-10125 -4875);
DOT 1 (-7450 -3025);
DOT 1 (-7525 -5900);
DOT 1 (-10125 -5700);
DOT 1 (-7525 -5850);
DOT 1 (-7250 -4250);
DOT 1 (-7175 -1375);
DOT 1 (-7450 -2975);
DOT 1 (-7250 -4700);
DOT 1 (-10225 -5550);
DOT 1 (-10225 -4875);
DOT 1 (-7175 -1825);
DOT 1 (-4875 -2775);
DOT 1 (-5250 -2725);
DOT 1 (-5625 -5650);
DOT 1 (-6300 -5600);
FORCENOTE
BMC TPM
(-11800 -5025) 0;
DISPLAY LEFT (-11800 -5025);
DISPLAY 2.510638 (-11800 -5025);
PAINT RED (-11800 -5025);
FORCENOTE
PCH TPM
(-10950 -1825) 0;
DISPLAY LEFT (-10950 -1825);
DISPLAY 2.510638 (-10950 -1825);
PAINT RED (-10950 -1825);
QUIT
